(kicad_sch (version 20230121) (generator eeschema)

  (paper "A3")

  (title_block
    (title "ECP5 - Datacenter Secure Control Module (DC-SCM)")
    (date "2024-07-15")
    (rev "1.2.1")
  )

  (junction (at 132.08 40.64) (diameter 0) (color 0 0 0 0)
  )
  (junction (at 128.27 199.39) (diameter 0) (color 0 0 0 0)
  )
  (junction (at 135.89 97.79) (diameter 0) (color 0 0 0 0)
  )
  (junction (at 124.46 250.19) (diameter 0) (color 0 0 0 0)
  )
  (junction (at 139.7 74.93) (diameter 0) (color 0 0 0 0)
  )
  (junction (at 124.46 97.79) (diameter 0) (color 0 0 0 0)
  )
  (junction (at 120.65 173.99) (diameter 0) (color 0 0 0 0)
  )
  (junction (at 120.65 40.64) (diameter 0) (color 0 0 0 0)
  )
  (junction (at 135.89 72.39) (diameter 0) (color 0 0 0 0)
  )
  (junction (at 124.46 228.6) (diameter 0) (color 0 0 0 0)
  )
  (junction (at 132.08 129.54) (diameter 0) (color 0 0 0 0)
  )
  (junction (at 120.65 194.31) (diameter 0) (color 0 0 0 0)
  )
  (junction (at 128.27 173.99) (diameter 0) (color 0 0 0 0)
  )
  (junction (at 124.46 40.64) (diameter 0) (color 0 0 0 0)
  )
  (junction (at 128.27 228.6) (diameter 0) (color 0 0 0 0)
  )
  (junction (at 120.65 97.79) (diameter 0) (color 0 0 0 0)
  )
  (junction (at 170.18 62.23) (diameter 0) (color 0 0 0 0)
  )
  (junction (at 120.65 228.6) (diameter 0) (color 0 0 0 0)
  )
  (junction (at 135.89 204.47) (diameter 0) (color 0 0 0 0)
  )
  (junction (at 120.65 247.65) (diameter 0) (color 0 0 0 0)
  )
  (junction (at 172.72 121.92) (diameter 0) (color 0 0 0 0)
  )
  (junction (at 124.46 124.46) (diameter 0) (color 0 0 0 0)
  )
  (junction (at 124.46 173.99) (diameter 0) (color 0 0 0 0)
  )
  (junction (at 135.89 228.6) (diameter 0) (color 0 0 0 0)
  )
  (junction (at 132.08 255.27) (diameter 0) (color 0 0 0 0)
  )
  (junction (at 132.08 228.6) (diameter 0) (color 0 0 0 0)
  )
  (junction (at 135.89 257.81) (diameter 0) (color 0 0 0 0)
  )
  (junction (at 139.7 207.01) (diameter 0) (color 0 0 0 0)
  )
  (junction (at 132.08 201.93) (diameter 0) (color 0 0 0 0)
  )
  (junction (at 124.46 196.85) (diameter 0) (color 0 0 0 0)
  )
  (junction (at 135.89 173.99) (diameter 0) (color 0 0 0 0)
  )
  (junction (at 132.08 173.99) (diameter 0) (color 0 0 0 0)
  )
  (junction (at 135.89 132.08) (diameter 0) (color 0 0 0 0)
  )
  (junction (at 132.08 97.79) (diameter 0) (color 0 0 0 0)
  )
  (junction (at 289.56 123.19) (diameter 0) (color 0 0 0 0)
  )
  (junction (at 120.65 62.23) (diameter 0) (color 0 0 0 0)
  )
  (junction (at 170.18 247.65) (diameter 0) (color 0 0 0 0)
  )
  (junction (at 139.7 134.62) (diameter 0) (color 0 0 0 0)
  )
  (junction (at 128.27 252.73) (diameter 0) (color 0 0 0 0)
  )
  (junction (at 124.46 64.77) (diameter 0) (color 0 0 0 0)
  )
  (junction (at 135.89 40.64) (diameter 0) (color 0 0 0 0)
  )
  (junction (at 120.65 121.92) (diameter 0) (color 0 0 0 0)
  )
  (junction (at 167.64 194.31) (diameter 0) (color 0 0 0 0)
  )
  (junction (at 139.7 260.35) (diameter 0) (color 0 0 0 0)
  )
  (junction (at 128.27 97.79) (diameter 0) (color 0 0 0 0)
  )
  (junction (at 128.27 67.31) (diameter 0) (color 0 0 0 0)
  )
  (junction (at 132.08 69.85) (diameter 0) (color 0 0 0 0)
  )
  (junction (at 128.27 40.64) (diameter 0) (color 0 0 0 0)
  )
  (junction (at 275.59 125.73) (diameter 0) (color 0 0 0 0)
  )
  (junction (at 128.27 127) (diameter 0) (color 0 0 0 0)
  )

  (no_connect (at 278.13 153.67))

  (wire (pts (xy 300.99 72.39) (xy 288.29 72.39))
    (stroke (width 0) (type default))
  )
  (wire (pts (xy 139.7 260.35) (xy 142.24 260.35))
    (stroke (width 0) (type default))
  )
  (wire (pts (xy 161.29 74.93) (xy 162.56 74.93))
    (stroke (width 0) (type default))
  )
  (wire (pts (xy 118.11 199.39) (xy 128.27 199.39))
    (stroke (width 0) (type default))
  )
  (wire (pts (xy 170.18 69.85) (xy 170.18 76.2))
    (stroke (width 0) (type default))
  )
  (wire (pts (xy 118.11 247.65) (xy 120.65 247.65))
    (stroke (width 0) (type default))
  )
  (wire (pts (xy 124.46 196.85) (xy 142.24 196.85))
    (stroke (width 0) (type default))
  )
  (wire (pts (xy 114.3 173.99) (xy 120.65 173.99))
    (stroke (width 0) (type default))
  )
  (wire (pts (xy 124.46 238.76) (xy 124.46 250.19))
    (stroke (width 0) (type default))
  )
  (wire (pts (xy 120.65 194.31) (xy 142.24 194.31))
    (stroke (width 0) (type default))
  )
  (wire (pts (xy 293.37 214.63) (xy 290.83 214.63))
    (stroke (width 0) (type default))
  )
  (wire (pts (xy 120.65 121.92) (xy 142.24 121.92))
    (stroke (width 0) (type default))
  )
  (wire (pts (xy 124.46 97.79) (xy 124.46 107.95))
    (stroke (width 0) (type default))
  )
  (wire (pts (xy 132.08 201.93) (xy 142.24 201.93))
    (stroke (width 0) (type default))
  )
  (wire (pts (xy 161.29 134.62) (xy 163.83 134.62))
    (stroke (width 0) (type default))
  )
  (wire (pts (xy 289.56 123.19) (xy 289.56 125.73))
    (stroke (width 0) (type default))
  )
  (wire (pts (xy 293.37 212.09) (xy 290.83 212.09))
    (stroke (width 0) (type default))
  )
  (wire (pts (xy 116.84 40.64) (xy 120.65 40.64))
    (stroke (width 0) (type default))
  )
  (wire (pts (xy 276.86 74.93) (xy 264.16 74.93))
    (stroke (width 0) (type default))
  )
  (wire (pts (xy 278.13 214.63) (xy 280.67 214.63))
    (stroke (width 0) (type default))
  )
  (wire (pts (xy 118.11 255.27) (xy 132.08 255.27))
    (stroke (width 0) (type default))
  )
  (wire (pts (xy 124.46 40.64) (xy 128.27 40.64))
    (stroke (width 0) (type default))
  )
  (wire (pts (xy 276.86 97.79) (xy 264.16 97.79))
    (stroke (width 0) (type default))
  )
  (wire (pts (xy 132.08 228.6) (xy 132.08 233.68))
    (stroke (width 0) (type default))
  )
  (wire (pts (xy 276.86 102.87) (xy 264.16 102.87))
    (stroke (width 0) (type default))
  )
  (wire (pts (xy 275.59 125.73) (xy 275.59 132.08))
    (stroke (width 0) (type default))
  )
  (wire (pts (xy 292.1 219.71) (xy 292.1 226.06))
    (stroke (width 0) (type default))
  )
  (wire (pts (xy 139.7 207.01) (xy 142.24 207.01))
    (stroke (width 0) (type default))
  )
  (wire (pts (xy 132.08 97.79) (xy 132.08 107.95))
    (stroke (width 0) (type default))
  )
  (wire (pts (xy 120.65 247.65) (xy 142.24 247.65))
    (stroke (width 0) (type default))
  )
  (wire (pts (xy 135.89 173.99) (xy 139.7 173.99))
    (stroke (width 0) (type default))
  )
  (wire (pts (xy 118.11 250.19) (xy 124.46 250.19))
    (stroke (width 0) (type default))
  )
  (wire (pts (xy 124.46 228.6) (xy 128.27 228.6))
    (stroke (width 0) (type default))
  )
  (wire (pts (xy 288.29 105.41) (xy 300.99 105.41))
    (stroke (width 0) (type default))
  )
  (wire (pts (xy 132.08 40.64) (xy 135.89 40.64))
    (stroke (width 0) (type default))
  )
  (wire (pts (xy 288.29 97.79) (xy 300.99 97.79))
    (stroke (width 0) (type default))
  )
  (wire (pts (xy 167.64 204.47) (xy 167.64 208.28))
    (stroke (width 0) (type default))
  )
  (wire (pts (xy 135.89 72.39) (xy 142.24 72.39))
    (stroke (width 0) (type default))
  )
  (wire (pts (xy 135.89 228.6) (xy 139.7 228.6))
    (stroke (width 0) (type default))
  )
  (wire (pts (xy 278.13 209.55) (xy 280.67 209.55))
    (stroke (width 0) (type default))
  )
  (wire (pts (xy 278.13 222.25) (xy 280.67 222.25))
    (stroke (width 0) (type default))
  )
  (wire (pts (xy 278.13 217.17) (xy 280.67 217.17))
    (stroke (width 0) (type default))
  )
  (wire (pts (xy 118.11 132.08) (xy 135.89 132.08))
    (stroke (width 0) (type default))
  )
  (wire (pts (xy 128.27 97.79) (xy 132.08 97.79))
    (stroke (width 0) (type default))
  )
  (wire (pts (xy 289.56 123.19) (xy 288.29 123.19))
    (stroke (width 0) (type default))
  )
  (wire (pts (xy 276.86 69.85) (xy 264.16 69.85))
    (stroke (width 0) (type default))
  )
  (wire (pts (xy 118.11 194.31) (xy 120.65 194.31))
    (stroke (width 0) (type default))
  )
  (wire (pts (xy 276.86 115.57) (xy 264.16 115.57))
    (stroke (width 0) (type default))
  )
  (wire (pts (xy 132.08 69.85) (xy 142.24 69.85))
    (stroke (width 0) (type default))
  )
  (wire (pts (xy 276.86 110.49) (xy 264.16 110.49))
    (stroke (width 0) (type default))
  )
  (wire (pts (xy 128.27 113.03) (xy 128.27 127))
    (stroke (width 0) (type default))
  )
  (wire (pts (xy 135.89 173.99) (xy 132.08 173.99))
    (stroke (width 0) (type default))
  )
  (wire (pts (xy 288.29 85.09) (xy 300.99 85.09))
    (stroke (width 0) (type default))
  )
  (wire (pts (xy 264.16 105.41) (xy 276.86 105.41))
    (stroke (width 0) (type default))
  )
  (wire (pts (xy 276.86 80.01) (xy 264.16 80.01))
    (stroke (width 0) (type default))
  )
  (wire (pts (xy 170.18 247.65) (xy 179.07 247.65))
    (stroke (width 0) (type default))
  )
  (wire (pts (xy 161.29 62.23) (xy 170.18 62.23))
    (stroke (width 0) (type default))
  )
  (wire (pts (xy 170.18 62.23) (xy 170.18 64.77))
    (stroke (width 0) (type default))
  )
  (wire (pts (xy 161.29 121.92) (xy 172.72 121.92))
    (stroke (width 0) (type default))
  )
  (wire (pts (xy 128.27 173.99) (xy 128.27 180.34))
    (stroke (width 0) (type default))
  )
  (wire (pts (xy 132.08 228.6) (xy 128.27 228.6))
    (stroke (width 0) (type default))
  )
  (wire (pts (xy 300.99 74.93) (xy 288.29 74.93))
    (stroke (width 0) (type default))
  )
  (wire (pts (xy 162.56 260.35) (xy 161.29 260.35))
    (stroke (width 0) (type default))
  )
  (wire (pts (xy 135.89 185.42) (xy 135.89 204.47))
    (stroke (width 0) (type default))
  )
  (wire (pts (xy 124.46 185.42) (xy 124.46 196.85))
    (stroke (width 0) (type default))
  )
  (wire (pts (xy 118.11 121.92) (xy 120.65 121.92))
    (stroke (width 0) (type default))
  )
  (wire (pts (xy 114.3 228.6) (xy 120.65 228.6))
    (stroke (width 0) (type default))
  )
  (wire (pts (xy 172.72 130.81) (xy 172.72 137.16))
    (stroke (width 0) (type default))
  )
  (wire (pts (xy 275.59 123.19) (xy 275.59 125.73))
    (stroke (width 0) (type default))
  )
  (wire (pts (xy 120.65 185.42) (xy 120.65 194.31))
    (stroke (width 0) (type default))
  )
  (wire (pts (xy 170.18 256.54) (xy 170.18 261.62))
    (stroke (width 0) (type default))
  )
  (wire (pts (xy 275.59 125.73) (xy 276.86 125.73))
    (stroke (width 0) (type default))
  )
  (wire (pts (xy 114.3 97.79) (xy 120.65 97.79))
    (stroke (width 0) (type default))
  )
  (wire (pts (xy 135.89 228.6) (xy 132.08 228.6))
    (stroke (width 0) (type default))
  )
  (wire (pts (xy 120.65 113.03) (xy 120.65 121.92))
    (stroke (width 0) (type default))
  )
  (wire (pts (xy 118.11 207.01) (xy 139.7 207.01))
    (stroke (width 0) (type default))
  )
  (wire (pts (xy 118.11 204.47) (xy 135.89 204.47))
    (stroke (width 0) (type default))
  )
  (wire (pts (xy 293.37 217.17) (xy 290.83 217.17))
    (stroke (width 0) (type default))
  )
  (wire (pts (xy 118.11 257.81) (xy 135.89 257.81))
    (stroke (width 0) (type default))
  )
  (wire (pts (xy 135.89 204.47) (xy 142.24 204.47))
    (stroke (width 0) (type default))
  )
  (wire (pts (xy 276.86 90.17) (xy 264.16 90.17))
    (stroke (width 0) (type default))
  )
  (wire (pts (xy 276.86 87.63) (xy 264.16 87.63))
    (stroke (width 0) (type default))
  )
  (wire (pts (xy 139.7 238.76) (xy 139.7 260.35))
    (stroke (width 0) (type default))
  )
  (wire (pts (xy 288.29 90.17) (xy 300.99 90.17))
    (stroke (width 0) (type default))
  )
  (wire (pts (xy 128.27 185.42) (xy 128.27 199.39))
    (stroke (width 0) (type default))
  )
  (wire (pts (xy 118.11 67.31) (xy 128.27 67.31))
    (stroke (width 0) (type default))
  )
  (wire (pts (xy 139.7 228.6) (xy 139.7 233.68))
    (stroke (width 0) (type default))
  )
  (wire (pts (xy 135.89 257.81) (xy 142.24 257.81))
    (stroke (width 0) (type default))
  )
  (wire (pts (xy 120.65 228.6) (xy 120.65 233.68))
    (stroke (width 0) (type default))
  )
  (wire (pts (xy 276.86 113.03) (xy 264.16 113.03))
    (stroke (width 0) (type default))
  )
  (wire (pts (xy 288.29 67.31) (xy 300.99 67.31))
    (stroke (width 0) (type default))
  )
  (wire (pts (xy 118.11 74.93) (xy 139.7 74.93))
    (stroke (width 0) (type default))
  )
  (wire (pts (xy 118.11 127) (xy 128.27 127))
    (stroke (width 0) (type default))
  )
  (wire (pts (xy 128.27 238.76) (xy 128.27 252.73))
    (stroke (width 0) (type default))
  )
  (wire (pts (xy 135.89 97.79) (xy 139.7 97.79))
    (stroke (width 0) (type default))
  )
  (wire (pts (xy 162.56 260.35) (xy 162.56 261.62))
    (stroke (width 0) (type default))
  )
  (wire (pts (xy 118.11 69.85) (xy 132.08 69.85))
    (stroke (width 0) (type default))
  )
  (wire (pts (xy 288.29 92.71) (xy 300.99 92.71))
    (stroke (width 0) (type default))
  )
  (wire (pts (xy 288.29 82.55) (xy 300.99 82.55))
    (stroke (width 0) (type default))
  )
  (wire (pts (xy 132.08 173.99) (xy 128.27 173.99))
    (stroke (width 0) (type default))
  )
  (wire (pts (xy 300.99 107.95) (xy 288.29 107.95))
    (stroke (width 0) (type default))
  )
  (wire (pts (xy 118.11 196.85) (xy 124.46 196.85))
    (stroke (width 0) (type default))
  )
  (wire (pts (xy 118.11 64.77) (xy 124.46 64.77))
    (stroke (width 0) (type default))
  )
  (wire (pts (xy 128.27 228.6) (xy 128.27 233.68))
    (stroke (width 0) (type default))
  )
  (wire (pts (xy 118.11 72.39) (xy 135.89 72.39))
    (stroke (width 0) (type default))
  )
  (wire (pts (xy 172.72 121.92) (xy 177.8 121.92))
    (stroke (width 0) (type default))
  )
  (wire (pts (xy 276.86 85.09) (xy 264.16 85.09))
    (stroke (width 0) (type default))
  )
  (wire (pts (xy 118.11 124.46) (xy 124.46 124.46))
    (stroke (width 0) (type default))
  )
  (wire (pts (xy 162.56 74.93) (xy 162.56 76.2))
    (stroke (width 0) (type default))
  )
  (wire (pts (xy 120.65 40.64) (xy 120.65 48.26))
    (stroke (width 0) (type default))
  )
  (wire (pts (xy 132.08 97.79) (xy 135.89 97.79))
    (stroke (width 0) (type default))
  )
  (wire (pts (xy 139.7 113.03) (xy 139.7 134.62))
    (stroke (width 0) (type default))
  )
  (wire (pts (xy 288.29 69.85) (xy 300.99 69.85))
    (stroke (width 0) (type default))
  )
  (wire (pts (xy 132.08 53.34) (xy 132.08 69.85))
    (stroke (width 0) (type default))
  )
  (wire (pts (xy 135.89 132.08) (xy 142.24 132.08))
    (stroke (width 0) (type default))
  )
  (wire (pts (xy 135.89 53.34) (xy 135.89 72.39))
    (stroke (width 0) (type default))
  )
  (wire (pts (xy 124.46 124.46) (xy 142.24 124.46))
    (stroke (width 0) (type default))
  )
  (wire (pts (xy 120.65 260.35) (xy 139.7 260.35))
    (stroke (width 0) (type default))
  )
  (wire (pts (xy 139.7 185.42) (xy 139.7 207.01))
    (stroke (width 0) (type default))
  )
  (wire (pts (xy 276.86 64.77) (xy 264.16 64.77))
    (stroke (width 0) (type default))
  )
  (wire (pts (xy 128.27 199.39) (xy 142.24 199.39))
    (stroke (width 0) (type default))
  )
  (wire (pts (xy 124.46 173.99) (xy 124.46 180.34))
    (stroke (width 0) (type default))
  )
  (wire (pts (xy 162.56 207.01) (xy 161.29 207.01))
    (stroke (width 0) (type default))
  )
  (wire (pts (xy 170.18 247.65) (xy 161.29 247.65))
    (stroke (width 0) (type default))
  )
  (wire (pts (xy 132.08 255.27) (xy 142.24 255.27))
    (stroke (width 0) (type default))
  )
  (wire (pts (xy 162.56 208.28) (xy 162.56 207.01))
    (stroke (width 0) (type default))
  )
  (wire (pts (xy 163.83 134.62) (xy 163.83 137.16))
    (stroke (width 0) (type default))
  )
  (wire (pts (xy 135.89 173.99) (xy 135.89 180.34))
    (stroke (width 0) (type default))
  )
  (wire (pts (xy 120.65 173.99) (xy 124.46 173.99))
    (stroke (width 0) (type default))
  )
  (wire (pts (xy 120.65 228.6) (xy 124.46 228.6))
    (stroke (width 0) (type default))
  )
  (wire (pts (xy 289.56 123.19) (xy 300.99 123.19))
    (stroke (width 0) (type default))
  )
  (wire (pts (xy 288.29 80.01) (xy 300.99 80.01))
    (stroke (width 0) (type default))
  )
  (wire (pts (xy 128.27 40.64) (xy 132.08 40.64))
    (stroke (width 0) (type default))
  )
  (wire (pts (xy 118.11 62.23) (xy 120.65 62.23))
    (stroke (width 0) (type default))
  )
  (wire (pts (xy 139.7 53.34) (xy 139.7 74.93))
    (stroke (width 0) (type default))
  )
  (wire (pts (xy 132.08 129.54) (xy 142.24 129.54))
    (stroke (width 0) (type default))
  )
  (wire (pts (xy 118.11 252.73) (xy 128.27 252.73))
    (stroke (width 0) (type default))
  )
  (wire (pts (xy 300.99 113.03) (xy 288.29 113.03))
    (stroke (width 0) (type default))
  )
  (wire (pts (xy 135.89 113.03) (xy 135.89 132.08))
    (stroke (width 0) (type default))
  )
  (wire (pts (xy 124.46 97.79) (xy 128.27 97.79))
    (stroke (width 0) (type default))
  )
  (wire (pts (xy 278.13 212.09) (xy 280.67 212.09))
    (stroke (width 0) (type default))
  )
  (wire (pts (xy 135.89 97.79) (xy 135.89 107.95))
    (stroke (width 0) (type default))
  )
  (wire (pts (xy 124.46 250.19) (xy 142.24 250.19))
    (stroke (width 0) (type default))
  )
  (wire (pts (xy 276.86 92.71) (xy 264.16 92.71))
    (stroke (width 0) (type default))
  )
  (wire (pts (xy 128.27 97.79) (xy 128.27 107.95))
    (stroke (width 0) (type default))
  )
  (wire (pts (xy 276.86 100.33) (xy 264.16 100.33))
    (stroke (width 0) (type default))
  )
  (wire (pts (xy 118.11 134.62) (xy 139.7 134.62))
    (stroke (width 0) (type default))
  )
  (wire (pts (xy 128.27 53.34) (xy 128.27 67.31))
    (stroke (width 0) (type default))
  )
  (wire (pts (xy 124.46 40.64) (xy 124.46 48.26))
    (stroke (width 0) (type default))
  )
  (wire (pts (xy 128.27 40.64) (xy 128.27 48.26))
    (stroke (width 0) (type default))
  )
  (wire (pts (xy 120.65 40.64) (xy 124.46 40.64))
    (stroke (width 0) (type default))
  )
  (wire (pts (xy 128.27 127) (xy 142.24 127))
    (stroke (width 0) (type default))
  )
  (wire (pts (xy 120.65 62.23) (xy 142.24 62.23))
    (stroke (width 0) (type default))
  )
  (wire (pts (xy 132.08 238.76) (xy 132.08 255.27))
    (stroke (width 0) (type default))
  )
  (wire (pts (xy 293.37 209.55) (xy 290.83 209.55))
    (stroke (width 0) (type default))
  )
  (wire (pts (xy 290.83 219.71) (xy 292.1 219.71))
    (stroke (width 0) (type default))
  )
  (wire (pts (xy 275.59 123.19) (xy 276.86 123.19))
    (stroke (width 0) (type default))
  )
  (wire (pts (xy 300.99 77.47) (xy 288.29 77.47))
    (stroke (width 0) (type default))
  )
  (wire (pts (xy 139.7 74.93) (xy 142.24 74.93))
    (stroke (width 0) (type default))
  )
  (wire (pts (xy 290.83 222.25) (xy 293.37 222.25))
    (stroke (width 0) (type default))
  )
  (wire (pts (xy 120.65 97.79) (xy 124.46 97.79))
    (stroke (width 0) (type default))
  )
  (wire (pts (xy 276.86 95.25) (xy 264.16 95.25))
    (stroke (width 0) (type default))
  )
  (wire (pts (xy 139.7 48.26) (xy 139.7 40.64))
    (stroke (width 0) (type default))
  )
  (wire (pts (xy 276.86 120.65) (xy 264.16 120.65))
    (stroke (width 0) (type default))
  )
  (wire (pts (xy 128.27 252.73) (xy 142.24 252.73))
    (stroke (width 0) (type default))
  )
  (wire (pts (xy 120.65 97.79) (xy 120.65 107.95))
    (stroke (width 0) (type default))
  )
  (wire (pts (xy 132.08 173.99) (xy 132.08 180.34))
    (stroke (width 0) (type default))
  )
  (wire (pts (xy 288.29 64.77) (xy 300.99 64.77))
    (stroke (width 0) (type default))
  )
  (wire (pts (xy 118.11 129.54) (xy 132.08 129.54))
    (stroke (width 0) (type default))
  )
  (wire (pts (xy 288.29 118.11) (xy 300.99 118.11))
    (stroke (width 0) (type default))
  )
  (wire (pts (xy 139.7 134.62) (xy 142.24 134.62))
    (stroke (width 0) (type default))
  )
  (wire (pts (xy 139.7 40.64) (xy 135.89 40.64))
    (stroke (width 0) (type default))
  )
  (wire (pts (xy 124.46 228.6) (xy 124.46 233.68))
    (stroke (width 0) (type default))
  )
  (wire (pts (xy 288.29 100.33) (xy 300.99 100.33))
    (stroke (width 0) (type default))
  )
  (wire (pts (xy 120.65 238.76) (xy 120.65 247.65))
    (stroke (width 0) (type default))
  )
  (wire (pts (xy 135.89 40.64) (xy 135.89 48.26))
    (stroke (width 0) (type default))
  )
  (wire (pts (xy 289.56 125.73) (xy 288.29 125.73))
    (stroke (width 0) (type default))
  )
  (wire (pts (xy 170.18 62.23) (xy 173.99 62.23))
    (stroke (width 0) (type default))
  )
  (wire (pts (xy 132.08 113.03) (xy 132.08 129.54))
    (stroke (width 0) (type default))
  )
  (wire (pts (xy 124.46 64.77) (xy 142.24 64.77))
    (stroke (width 0) (type default))
  )
  (wire (pts (xy 135.89 238.76) (xy 135.89 257.81))
    (stroke (width 0) (type default))
  )
  (wire (pts (xy 276.86 67.31) (xy 264.16 67.31))
    (stroke (width 0) (type default))
  )
  (wire (pts (xy 276.86 77.47) (xy 264.16 77.47))
    (stroke (width 0) (type default))
  )
  (wire (pts (xy 167.64 194.31) (xy 170.18 194.31))
    (stroke (width 0) (type default))
  )
  (wire (pts (xy 139.7 97.79) (xy 139.7 107.95))
    (stroke (width 0) (type default))
  )
  (wire (pts (xy 276.86 118.11) (xy 264.16 118.11))
    (stroke (width 0) (type default))
  )
  (wire (pts (xy 132.08 185.42) (xy 132.08 201.93))
    (stroke (width 0) (type default))
  )
  (wire (pts (xy 170.18 247.65) (xy 170.18 251.46))
    (stroke (width 0) (type default))
  )
  (wire (pts (xy 124.46 53.34) (xy 124.46 64.77))
    (stroke (width 0) (type default))
  )
  (wire (pts (xy 132.08 40.64) (xy 132.08 48.26))
    (stroke (width 0) (type default))
  )
  (wire (pts (xy 300.99 110.49) (xy 288.29 110.49))
    (stroke (width 0) (type default))
  )
  (wire (pts (xy 128.27 67.31) (xy 142.24 67.31))
    (stroke (width 0) (type default))
  )
  (wire (pts (xy 288.29 102.87) (xy 300.99 102.87))
    (stroke (width 0) (type default))
  )
  (wire (pts (xy 172.72 121.92) (xy 172.72 125.73))
    (stroke (width 0) (type default))
  )
  (wire (pts (xy 120.65 53.34) (xy 120.65 62.23))
    (stroke (width 0) (type default))
  )
  (wire (pts (xy 279.4 219.71) (xy 279.4 226.06))
    (stroke (width 0) (type default))
  )
  (wire (pts (xy 276.86 72.39) (xy 264.16 72.39))
    (stroke (width 0) (type default))
  )
  (wire (pts (xy 124.46 173.99) (xy 128.27 173.99))
    (stroke (width 0) (type default))
  )
  (wire (pts (xy 120.65 173.99) (xy 120.65 180.34))
    (stroke (width 0) (type default))
  )
  (wire (pts (xy 139.7 173.99) (xy 139.7 180.34))
    (stroke (width 0) (type default))
  )
  (wire (pts (xy 124.46 113.03) (xy 124.46 124.46))
    (stroke (width 0) (type default))
  )
  (wire (pts (xy 276.86 107.95) (xy 264.16 107.95))
    (stroke (width 0) (type default))
  )
  (wire (pts (xy 288.29 120.65) (xy 300.99 120.65))
    (stroke (width 0) (type default))
  )
  (wire (pts (xy 300.99 115.57) (xy 288.29 115.57))
    (stroke (width 0) (type default))
  )
  (wire (pts (xy 167.64 194.31) (xy 167.64 199.39))
    (stroke (width 0) (type default))
  )
  (wire (pts (xy 276.86 82.55) (xy 264.16 82.55))
    (stroke (width 0) (type default))
  )
  (wire (pts (xy 161.29 194.31) (xy 167.64 194.31))
    (stroke (width 0) (type default))
  )
  (wire (pts (xy 288.29 95.25) (xy 300.99 95.25))
    (stroke (width 0) (type default))
  )
  (wire (pts (xy 118.11 201.93) (xy 132.08 201.93))
    (stroke (width 0) (type default))
  )
  (wire (pts (xy 288.29 87.63) (xy 300.99 87.63))
    (stroke (width 0) (type default))
  )
  (wire (pts (xy 280.67 219.71) (xy 279.4 219.71))
    (stroke (width 0) (type default))
  )
  (wire (pts (xy 135.89 228.6) (xy 135.89 233.68))
    (stroke (width 0) (type default))
  )

  (text "BMC flash" (at 139.7 165.1 0)
    (effects (font (size 2.9972 2.9972)) (justify left bottom))
  )
  (text "One or typically two flash devices used to contain the BIOS firmware image"
    (at 111.76 34.925 0)
    (effects (font (size 1.27 1.27)) (justify left bottom))
  )
  (text "preliminary\n" (at 276.86 53.34 0)
    (effects (font (size 1.27 1.27)) (justify left bottom))
  )
  (text "BIOS flash" (at 135.89 31.75 0)
    (effects (font (size 2.9972 2.9972)) (justify left bottom))
  )
  (text "Pinout for AES-PMOD-TPM20-SLB9670-G" (at 265.43 200.66 0)
    (effects (font (size 1.27 1.27)) (justify left bottom))
  )
  (text "RoT connector" (at 266.7 50.8 0)
    (effects (font (size 2.9972 2.9972)) (justify left bottom))
  )
  (text "One or typically two flash devices used to contain the BMC firmware image"
    (at 116.84 167.64 0)
    (effects (font (size 1.27 1.27)) (justify left bottom))
  )
  (text "TPM connector" (at 270.51 198.12 0)
    (effects (font (size 2.9972 2.9972)) (justify left bottom))
  )

  (global_label "QSPIA1_D1" (shape input) (at 264.16 115.57 180) (fields_autoplaced)
    (effects (font (size 1.27 1.27)) (justify right))
    (property "Intersheetrefs" "${INTERSHEET_REFS}" (at 55.245 -45.085 0)
      (effects (font (size 1.27 1.27)) hide)
    )
  )
  (global_label "QSPIB2_D1" (shape input) (at 118.11 250.19 180) (fields_autoplaced)
    (effects (font (size 1.27 1.27)) (justify right))
    (property "Intersheetrefs" "${INTERSHEET_REFS}" (at 215.9 2.54 0)
      (effects (font (size 1.27 1.27)) hide)
    )
  )
  (global_label "PP" (shape input) (at 293.37 217.17 0) (fields_autoplaced)
    (effects (font (size 1.27 1.27)) (justify left))
    (property "Intersheetrefs" "${INTERSHEET_REFS}" (at -9.525 158.75 0)
      (effects (font (size 1.27 1.27)) hide)
    )
  )
  (global_label "QSPIB1_CS_N" (shape input) (at 118.11 207.01 180) (fields_autoplaced)
    (effects (font (size 1.27 1.27)) (justify right))
    (property "Intersheetrefs" "${INTERSHEET_REFS}" (at 70.485 16.51 0)
      (effects (font (size 1.27 1.27)) hide)
    )
  )
  (global_label "QSPIB_CLK" (shape input) (at 300.99 77.47 0) (fields_autoplaced)
    (effects (font (size 1.27 1.27)) (justify left))
    (property "Intersheetrefs" "${INTERSHEET_REFS}" (at 55.245 -45.085 0)
      (effects (font (size 1.27 1.27)) hide)
    )
  )
  (global_label "QSPI0_D3" (shape input) (at 264.16 92.71 180) (fields_autoplaced)
    (effects (font (size 1.27 1.27)) (justify right))
    (property "Intersheetrefs" "${INTERSHEET_REFS}" (at 55.245 -45.085 0)
      (effects (font (size 1.27 1.27)) hide)
    )
  )
  (global_label "QSPIB1_D1" (shape input) (at 118.11 196.85 180) (fields_autoplaced)
    (effects (font (size 1.27 1.27)) (justify right))
    (property "Intersheetrefs" "${INTERSHEET_REFS}" (at 216.535 1.27 0)
      (effects (font (size 1.27 1.27)) (justify left) hide)
    )
  )
  (global_label "PROGRAM_N" (shape input) (at 264.16 77.47 180) (fields_autoplaced)
    (effects (font (size 1.27 1.27)) (justify right))
    (property "Intersheetrefs" "${INTERSHEET_REFS}" (at 55.245 -45.085 0)
      (effects (font (size 1.27 1.27)) hide)
    )
  )
  (global_label "QSPIA_CLK" (shape input) (at 300.99 105.41 0) (fields_autoplaced)
    (effects (font (size 1.27 1.27)) (justify left))
    (property "Intersheetrefs" "${INTERSHEET_REFS}" (at 55.245 -45.085 0)
      (effects (font (size 1.27 1.27)) hide)
    )
  )
  (global_label "ROT_QSPI_DQ2" (shape input) (at 264.16 85.09 180) (fields_autoplaced)
    (effects (font (size 1.27 1.27)) (justify right))
    (property "Intersheetrefs" "${INTERSHEET_REFS}" (at 55.245 -45.085 0)
      (effects (font (size 1.27 1.27)) hide)
    )
  )
  (global_label "QSPIB2_D1" (shape input) (at 300.99 85.09 0) (fields_autoplaced)
    (effects (font (size 1.27 1.27)) (justify left))
    (property "Intersheetrefs" "${INTERSHEET_REFS}" (at 55.245 -45.085 0)
      (effects (font (size 1.27 1.27)) hide)
    )
  )
  (global_label "QSPIA2_D0" (shape input) (at 118.11 121.92 180) (fields_autoplaced)
    (effects (font (size 1.27 1.27)) (justify right))
    (property "Intersheetrefs" "${INTERSHEET_REFS}" (at 69.215 0 0)
      (effects (font (size 1.27 1.27)) hide)
    )
  )
  (global_label "QSPIB1_D2" (shape input) (at 118.11 199.39 180) (fields_autoplaced)
    (effects (font (size 1.27 1.27)) (justify right))
    (property "Intersheetrefs" "${INTERSHEET_REFS}" (at 70.485 6.35 0)
      (effects (font (size 1.27 1.27)) hide)
    )
  )
  (global_label "QSPI0_CS0_N" (shape input) (at 264.16 102.87 180) (fields_autoplaced)
    (effects (font (size 1.27 1.27)) (justify right))
    (property "Intersheetrefs" "${INTERSHEET_REFS}" (at 55.245 -45.085 0)
      (effects (font (size 1.27 1.27)) hide)
    )
  )
  (global_label "QSPIB2_D0" (shape input) (at 300.99 74.93 0) (fields_autoplaced)
    (effects (font (size 1.27 1.27)) (justify left))
    (property "Intersheetrefs" "${INTERSHEET_REFS}" (at 55.245 -45.085 0)
      (effects (font (size 1.27 1.27)) hide)
    )
  )
  (global_label "ROT_QSPI_DQ1" (shape input) (at 264.16 82.55 180) (fields_autoplaced)
    (effects (font (size 1.27 1.27)) (justify right))
    (property "Intersheetrefs" "${INTERSHEET_REFS}" (at 55.245 -45.085 0)
      (effects (font (size 1.27 1.27)) hide)
    )
  )
  (global_label "ROT_SCLK" (shape input) (at 264.16 64.77 180) (fields_autoplaced)
    (effects (font (size 1.27 1.27)) (justify right))
    (property "Intersheetrefs" "${INTERSHEET_REFS}" (at 55.245 -45.085 0)
      (effects (font (size 1.27 1.27)) hide)
    )
  )
  (global_label "QSPIB1_D0" (shape input) (at 118.11 194.31 180) (fields_autoplaced)
    (effects (font (size 1.27 1.27)) (justify right))
    (property "Intersheetrefs" "${INTERSHEET_REFS}" (at 70.485 -1.27 0)
      (effects (font (size 1.27 1.27)) hide)
    )
  )
  (global_label "QSPIB2_CS_N" (shape input) (at 120.65 260.35 180) (fields_autoplaced)
    (effects (font (size 1.27 1.27)) (justify right))
    (property "Intersheetrefs" "${INTERSHEET_REFS}" (at 73.66 17.78 0)
      (effects (font (size 1.27 1.27)) hide)
    )
  )
  (global_label "VCC3V3" (shape input) (at 116.84 40.64 180) (fields_autoplaced)
    (effects (font (size 1.27 1.27)) (justify right))
    (property "Intersheetrefs" "${INTERSHEET_REFS}" (at 107.3728 40.64 0)
      (effects (font (size 1.27 1.27)) (justify right) hide)
    )
  )
  (global_label "ROT_RDY\\ROT_GPIO0" (shape input) (at 264.16 72.39 180) (fields_autoplaced)
    (effects (font (size 1.27 1.27)) (justify right))
    (property "Intersheetrefs" "${INTERSHEET_REFS}" (at 55.245 -45.085 0)
      (effects (font (size 1.27 1.27)) hide)
    )
  )
  (global_label "QSPIA1_D0" (shape input) (at 264.16 107.95 180) (fields_autoplaced)
    (effects (font (size 1.27 1.27)) (justify right))
    (property "Intersheetrefs" "${INTERSHEET_REFS}" (at 55.245 -45.085 0)
      (effects (font (size 1.27 1.27)) hide)
    )
  )
  (global_label "ROT_QSPI_DQ3" (shape input) (at 264.16 87.63 180) (fields_autoplaced)
    (effects (font (size 1.27 1.27)) (justify right))
    (property "Intersheetrefs" "${INTERSHEET_REFS}" (at 55.245 -45.085 0)
      (effects (font (size 1.27 1.27)) hide)
    )
  )
  (global_label "QSPIB1_D3" (shape input) (at 300.99 92.71 0) (fields_autoplaced)
    (effects (font (size 1.27 1.27)) (justify left))
    (property "Intersheetrefs" "${INTERSHEET_REFS}" (at 55.245 -45.085 0)
      (effects (font (size 1.27 1.27)) hide)
    )
  )
  (global_label "QSPI0_CLK" (shape input) (at 264.16 105.41 180) (fields_autoplaced)
    (effects (font (size 1.27 1.27)) (justify right))
    (property "Intersheetrefs" "${INTERSHEET_REFS}" (at 55.245 -45.085 0)
      (effects (font (size 1.27 1.27)) hide)
    )
  )
  (global_label "VCC3V3" (shape input) (at 177.8 121.92 0) (fields_autoplaced)
    (effects (font (size 1.27 1.27)) (justify left))
    (property "Intersheetrefs" "${INTERSHEET_REFS}" (at 187.2672 121.92 0)
      (effects (font (size 1.27 1.27)) (justify left) hide)
    )
  )
  (global_label "QSPIA1_D2" (shape input) (at 118.11 67.31 180) (fields_autoplaced)
    (effects (font (size 1.27 1.27)) (justify right))
    (property "Intersheetrefs" "${INTERSHEET_REFS}" (at 68.58 0 0)
      (effects (font (size 1.27 1.27)) hide)
    )
  )
  (global_label "VCC3V3" (shape input) (at 173.99 62.23 0) (fields_autoplaced)
    (effects (font (size 1.27 1.27)) (justify left))
    (property "Intersheetrefs" "${INTERSHEET_REFS}" (at 183.4572 62.23 0)
      (effects (font (size 1.27 1.27)) (justify left) hide)
    )
  )
  (global_label "QSPIA_CLK" (shape input) (at 118.11 132.08 180) (fields_autoplaced)
    (effects (font (size 1.27 1.27)) (justify right))
    (property "Intersheetrefs" "${INTERSHEET_REFS}" (at 69.215 7.62 0)
      (effects (font (size 1.27 1.27)) hide)
    )
  )
  (global_label "ROT_RX" (shape input) (at 264.16 67.31 180) (fields_autoplaced)
    (effects (font (size 1.27 1.27)) (justify right))
    (property "Intersheetrefs" "${INTERSHEET_REFS}" (at 55.245 -45.085 0)
      (effects (font (size 1.27 1.27)) hide)
    )
  )
  (global_label "QSPIA2_D1" (shape input) (at 118.11 124.46 180) (fields_autoplaced)
    (effects (font (size 1.27 1.27)) (justify right))
    (property "Intersheetrefs" "${INTERSHEET_REFS}" (at 217.805 2.54 0)
      (effects (font (size 1.27 1.27)) (justify left) hide)
    )
  )
  (global_label "QSPIB2_D3" (shape input) (at 118.11 255.27 180) (fields_autoplaced)
    (effects (font (size 1.27 1.27)) (justify right))
    (property "Intersheetrefs" "${INTERSHEET_REFS}" (at 71.12 2.54 0)
      (effects (font (size 1.27 1.27)) hide)
    )
  )
  (global_label "RST" (shape input) (at 293.37 212.09 0) (fields_autoplaced)
    (effects (font (size 1.27 1.27)) (justify left))
    (property "Intersheetrefs" "${INTERSHEET_REFS}" (at -9.525 158.75 0)
      (effects (font (size 1.27 1.27)) hide)
    )
  )
  (global_label "VCC3V3" (shape input) (at 170.18 194.31 0) (fields_autoplaced)
    (effects (font (size 1.27 1.27)) (justify left))
    (property "Intersheetrefs" "${INTERSHEET_REFS}" (at 179.6472 194.31 0)
      (effects (font (size 1.27 1.27)) (justify left) hide)
    )
  )
  (global_label "ROT_QSPI_DQ0" (shape input) (at 264.16 80.01 180) (fields_autoplaced)
    (effects (font (size 1.27 1.27)) (justify right))
    (property "Intersheetrefs" "${INTERSHEET_REFS}" (at 55.245 -45.085 0)
      (effects (font (size 1.27 1.27)) hide)
    )
  )
  (global_label "ROT_TX" (shape input) (at 264.16 69.85 180) (fields_autoplaced)
    (effects (font (size 1.27 1.27)) (justify right))
    (property "Intersheetrefs" "${INTERSHEET_REFS}" (at 55.245 -45.085 0)
      (effects (font (size 1.27 1.27)) hide)
    )
  )
  (global_label "VCC3V3" (shape input) (at 300.99 123.19 0) (fields_autoplaced)
    (effects (font (size 1.27 1.27)) (justify left))
    (property "Intersheetrefs" "${INTERSHEET_REFS}" (at 55.245 -45.085 0)
      (effects (font (size 1.27 1.27)) hide)
    )
  )
  (global_label "QSPIB2_D0" (shape input) (at 118.11 247.65 180) (fields_autoplaced)
    (effects (font (size 1.27 1.27)) (justify right))
    (property "Intersheetrefs" "${INTERSHEET_REFS}" (at 71.12 0 0)
      (effects (font (size 1.27 1.27)) hide)
    )
  )
  (global_label "QSPI0_CS1_N" (shape input) (at 300.99 118.11 0) (fields_autoplaced)
    (effects (font (size 1.27 1.27)) (justify left))
    (property "Intersheetrefs" "${INTERSHEET_REFS}" (at 55.245 -45.085 0)
      (effects (font (size 1.27 1.27)) hide)
    )
  )
  (global_label "VCC3V3" (shape input) (at 293.37 222.25 0) (fields_autoplaced)
    (effects (font (size 1.27 1.27)) (justify left))
    (property "Intersheetrefs" "${INTERSHEET_REFS}" (at 302.8372 222.25 0)
      (effects (font (size 1.27 1.27)) (justify left) hide)
    )
  )
  (global_label "QSPIA1_D2" (shape input) (at 264.16 118.11 180) (fields_autoplaced)
    (effects (font (size 1.27 1.27)) (justify right))
    (property "Intersheetrefs" "${INTERSHEET_REFS}" (at 55.245 -45.085 0)
      (effects (font (size 1.27 1.27)) hide)
    )
  )
  (global_label "VCC3V3" (shape input) (at 114.3 97.79 180) (fields_autoplaced)
    (effects (font (size 1.27 1.27)) (justify right))
    (property "Intersheetrefs" "${INTERSHEET_REFS}" (at 104.8328 97.79 0)
      (effects (font (size 1.27 1.27)) (justify right) hide)
    )
  )
  (global_label "QSPI0_D1" (shape input) (at 264.16 97.79 180) (fields_autoplaced)
    (effects (font (size 1.27 1.27)) (justify right))
    (property "Intersheetrefs" "${INTERSHEET_REFS}" (at 55.245 -45.085 0)
      (effects (font (size 1.27 1.27)) hide)
    )
  )
  (global_label "QSPIB1_CS_N" (shape input) (at 300.99 95.25 0) (fields_autoplaced)
    (effects (font (size 1.27 1.27)) (justify left))
    (property "Intersheetrefs" "${INTERSHEET_REFS}" (at 55.245 -45.085 0)
      (effects (font (size 1.27 1.27)) hide)
    )
  )
  (global_label "VCC3V3" (shape input) (at 179.07 247.65 0) (fields_autoplaced)
    (effects (font (size 1.27 1.27)) (justify left))
    (property "Intersheetrefs" "${INTERSHEET_REFS}" (at 188.5372 247.65 0)
      (effects (font (size 1.27 1.27)) (justify left) hide)
    )
  )
  (global_label "QSPIB1_D3" (shape input) (at 118.11 201.93 180) (fields_autoplaced)
    (effects (font (size 1.27 1.27)) (justify right))
    (property "Intersheetrefs" "${INTERSHEET_REFS}" (at 70.485 1.27 0)
      (effects (font (size 1.27 1.27)) hide)
    )
  )
  (global_label "QSPIB1_D2" (shape input) (at 300.99 100.33 0) (fields_autoplaced)
    (effects (font (size 1.27 1.27)) (justify left))
    (property "Intersheetrefs" "${INTERSHEET_REFS}" (at 55.245 -45.085 0)
      (effects (font (size 1.27 1.27)) hide)
    )
  )
  (global_label "QSPI0_D0" (shape input) (at 264.16 100.33 180) (fields_autoplaced)
    (effects (font (size 1.27 1.27)) (justify right))
    (property "Intersheetrefs" "${INTERSHEET_REFS}" (at 55.245 -45.085 0)
      (effects (font (size 1.27 1.27)) hide)
    )
  )
  (global_label "QSPIA1_D3" (shape input) (at 264.16 110.49 180) (fields_autoplaced)
    (effects (font (size 1.27 1.27)) (justify right))
    (property "Intersheetrefs" "${INTERSHEET_REFS}" (at 55.245 -45.085 0)
      (effects (font (size 1.27 1.27)) hide)
    )
  )
  (global_label "VCC3V3" (shape input) (at 114.3 173.99 180) (fields_autoplaced)
    (effects (font (size 1.27 1.27)) (justify right))
    (property "Intersheetrefs" "${INTERSHEET_REFS}" (at 104.8328 173.99 0)
      (effects (font (size 1.27 1.27)) (justify right) hide)
    )
  )
  (global_label "QSPIB2_CS_N" (shape input) (at 300.99 82.55 0) (fields_autoplaced)
    (effects (font (size 1.27 1.27)) (justify left))
    (property "Intersheetrefs" "${INTERSHEET_REFS}" (at 55.245 -45.085 0)
      (effects (font (size 1.27 1.27)) hide)
    )
  )
  (global_label "ROT_SS" (shape input) (at 300.99 69.85 0) (fields_autoplaced)
    (effects (font (size 1.27 1.27)) (justify left))
    (property "Intersheetrefs" "${INTERSHEET_REFS}" (at 55.245 -45.085 0)
      (effects (font (size 1.27 1.27)) hide)
    )
  )
  (global_label "PIRQ#" (shape input) (at 293.37 209.55 0) (fields_autoplaced)
    (effects (font (size 1.27 1.27)) (justify left))
    (property "Intersheetrefs" "${INTERSHEET_REFS}" (at -9.525 158.75 0)
      (effects (font (size 1.27 1.27)) hide)
    )
  )
  (global_label "VCC3V3" (shape input) (at 278.13 222.25 180) (fields_autoplaced)
    (effects (font (size 1.27 1.27)) (justify right))
    (property "Intersheetrefs" "${INTERSHEET_REFS}" (at 268.6628 222.25 0)
      (effects (font (size 1.27 1.27)) (justify right) hide)
    )
  )
  (global_label "ROT_GPIO2" (shape input) (at 264.16 120.65 180) (fields_autoplaced)
    (effects (font (size 1.27 1.27)) (justify right))
    (property "Intersheetrefs" "${INTERSHEET_REFS}" (at 55.245 -45.085 0)
      (effects (font (size 1.27 1.27)) hide)
    )
  )
  (global_label "QSPIA2_D3" (shape input) (at 300.99 107.95 0) (fields_autoplaced)
    (effects (font (size 1.27 1.27)) (justify left))
    (property "Intersheetrefs" "${INTERSHEET_REFS}" (at 55.245 -45.085 0)
      (effects (font (size 1.27 1.27)) hide)
    )
  )
  (global_label "INIT_N" (shape input) (at 264.16 74.93 180) (fields_autoplaced)
    (effects (font (size 1.27 1.27)) (justify right))
    (property "Intersheetrefs" "${INTERSHEET_REFS}" (at 55.245 -45.085 0)
      (effects (font (size 1.27 1.27)) hide)
    )
  )
  (global_label "QSPIB1_D0" (shape input) (at 300.99 90.17 0) (fields_autoplaced)
    (effects (font (size 1.27 1.27)) (justify left))
    (property "Intersheetrefs" "${INTERSHEET_REFS}" (at 55.245 -45.085 0)
      (effects (font (size 1.27 1.27)) hide)
    )
  )
  (global_label "QSPIB2_D3" (shape input) (at 300.99 80.01 0) (fields_autoplaced)
    (effects (font (size 1.27 1.27)) (justify left))
    (property "Intersheetrefs" "${INTERSHEET_REFS}" (at 55.245 -45.085 0)
      (effects (font (size 1.27 1.27)) hide)
    )
  )
  (global_label "QSPIB2_D2" (shape input) (at 118.11 252.73 180) (fields_autoplaced)
    (effects (font (size 1.27 1.27)) (justify right))
    (property "Intersheetrefs" "${INTERSHEET_REFS}" (at 71.12 7.62 0)
      (effects (font (size 1.27 1.27)) hide)
    )
  )
  (global_label "QSPI0_D2" (shape input) (at 264.16 95.25 180) (fields_autoplaced)
    (effects (font (size 1.27 1.27)) (justify right))
    (property "Intersheetrefs" "${INTERSHEET_REFS}" (at 55.245 -45.085 0)
      (effects (font (size 1.27 1.27)) hide)
    )
  )
  (global_label "QSPIA1_D1" (shape input) (at 118.11 64.77 180) (fields_autoplaced)
    (effects (font (size 1.27 1.27)) (justify right))
    (property "Intersheetrefs" "${INTERSHEET_REFS}" (at 218.44 -5.08 0)
      (effects (font (size 1.27 1.27)) (justify left) hide)
    )
  )
  (global_label "QSPIA2_D2" (shape input) (at 118.11 127 180) (fields_autoplaced)
    (effects (font (size 1.27 1.27)) (justify right))
    (property "Intersheetrefs" "${INTERSHEET_REFS}" (at 69.215 7.62 0)
      (effects (font (size 1.27 1.27)) hide)
    )
  )
  (global_label "QSPIA1_D0" (shape input) (at 118.11 62.23 180) (fields_autoplaced)
    (effects (font (size 1.27 1.27)) (justify right))
    (property "Intersheetrefs" "${INTERSHEET_REFS}" (at 68.58 -7.62 0)
      (effects (font (size 1.27 1.27)) hide)
    )
  )
  (global_label "QSPIA_CLK" (shape input) (at 118.11 72.39 180) (fields_autoplaced)
    (effects (font (size 1.27 1.27)) (justify right))
    (property "Intersheetrefs" "${INTERSHEET_REFS}" (at 68.58 0 0)
      (effects (font (size 1.27 1.27)) hide)
    )
  )
  (global_label "SPI0_CS_N" (shape input) (at 278.13 209.55 180) (fields_autoplaced)
    (effects (font (size 1.27 1.27)) (justify right))
    (property "Intersheetrefs" "${INTERSHEET_REFS}" (at -14.605 158.75 0)
      (effects (font (size 1.27 1.27)) hide)
    )
  )
  (global_label "SPI0_MISO" (shape input) (at 278.13 214.63 180) (fields_autoplaced)
    (effects (font (size 1.27 1.27)) (justify right))
    (property "Intersheetrefs" "${INTERSHEET_REFS}" (at -14.605 158.75 0)
      (effects (font (size 1.27 1.27)) hide)
    )
  )
  (global_label "QSPIB_CLK" (shape input) (at 118.11 257.81 180) (fields_autoplaced)
    (effects (font (size 1.27 1.27)) (justify right))
    (property "Intersheetrefs" "${INTERSHEET_REFS}" (at 71.12 7.62 0)
      (effects (font (size 1.27 1.27)) hide)
    )
  )
  (global_label "QSPIA1_CS_N" (shape input) (at 118.11 74.93 180) (fields_autoplaced)
    (effects (font (size 1.27 1.27)) (justify right))
    (property "Intersheetrefs" "${INTERSHEET_REFS}" (at 68.58 10.16 0)
      (effects (font (size 1.27 1.27)) hide)
    )
  )
  (global_label "ROT_MOSI" (shape input) (at 300.99 64.77 0) (fields_autoplaced)
    (effects (font (size 1.27 1.27)) (justify left))
    (property "Intersheetrefs" "${INTERSHEET_REFS}" (at 55.245 -45.085 0)
      (effects (font (size 1.27 1.27)) hide)
    )
  )
  (global_label "SPI0_MOSI" (shape input) (at 278.13 212.09 180) (fields_autoplaced)
    (effects (font (size 1.27 1.27)) (justify right))
    (property "Intersheetrefs" "${INTERSHEET_REFS}" (at -14.605 158.75 0)
      (effects (font (size 1.27 1.27)) hide)
    )
  )
  (global_label "VCC3V3" (shape input) (at 114.3 228.6 180) (fields_autoplaced)
    (effects (font (size 1.27 1.27)) (justify right))
    (property "Intersheetrefs" "${INTERSHEET_REFS}" (at 104.8328 228.6 0)
      (effects (font (size 1.27 1.27)) (justify right) hide)
    )
  )
  (global_label "ROT_MISO" (shape input) (at 300.99 67.31 0) (fields_autoplaced)
    (effects (font (size 1.27 1.27)) (justify left))
    (property "Intersheetrefs" "${INTERSHEET_REFS}" (at 55.245 -45.085 0)
      (effects (font (size 1.27 1.27)) hide)
    )
  )
  (global_label "QSPIA2_D3" (shape input) (at 118.11 129.54 180) (fields_autoplaced)
    (effects (font (size 1.27 1.27)) (justify right))
    (property "Intersheetrefs" "${INTERSHEET_REFS}" (at 69.215 2.54 0)
      (effects (font (size 1.27 1.27)) hide)
    )
  )
  (global_label "QSPIA2_D1" (shape input) (at 300.99 113.03 0) (fields_autoplaced)
    (effects (font (size 1.27 1.27)) (justify left))
    (property "Intersheetrefs" "${INTERSHEET_REFS}" (at 55.245 -45.085 0)
      (effects (font (size 1.27 1.27)) hide)
    )
  )
  (global_label "QSPIA2_CS_N" (shape input) (at 300.99 110.49 0) (fields_autoplaced)
    (effects (font (size 1.27 1.27)) (justify left))
    (property "Intersheetrefs" "${INTERSHEET_REFS}" (at 55.245 -45.085 0)
      (effects (font (size 1.27 1.27)) hide)
    )
  )
  (global_label "SPI0_CLK" (shape input) (at 278.13 217.17 180) (fields_autoplaced)
    (effects (font (size 1.27 1.27)) (justify right))
    (property "Intersheetrefs" "${INTERSHEET_REFS}" (at -14.605 158.75 0)
      (effects (font (size 1.27 1.27)) hide)
    )
  )
  (global_label "QSPIA1_CS_N" (shape input) (at 264.16 113.03 180) (fields_autoplaced)
    (effects (font (size 1.27 1.27)) (justify right))
    (property "Intersheetrefs" "${INTERSHEET_REFS}" (at 55.245 -45.085 0)
      (effects (font (size 1.27 1.27)) hide)
    )
  )
  (global_label "QSPIA2_D0" (shape input) (at 300.99 102.87 0) (fields_autoplaced)
    (effects (font (size 1.27 1.27)) (justify left))
    (property "Intersheetrefs" "${INTERSHEET_REFS}" (at 55.245 -45.085 0)
      (effects (font (size 1.27 1.27)) hide)
    )
  )
  (global_label "ROT_QSPI_CS_N" (shape input) (at 300.99 72.39 0) (fields_autoplaced)
    (effects (font (size 1.27 1.27)) (justify left))
    (property "Intersheetrefs" "${INTERSHEET_REFS}" (at 55.245 -45.085 0)
      (effects (font (size 1.27 1.27)) hide)
    )
  )
  (global_label "ROT_GPIO1" (shape input) (at 300.99 120.65 0) (fields_autoplaced)
    (effects (font (size 1.27 1.27)) (justify left))
    (property "Intersheetrefs" "${INTERSHEET_REFS}" (at 55.245 -45.085 0)
      (effects (font (size 1.27 1.27)) hide)
    )
  )
  (global_label "QSPIB_CLK" (shape input) (at 118.11 204.47 180) (fields_autoplaced)
    (effects (font (size 1.27 1.27)) (justify right))
    (property "Intersheetrefs" "${INTERSHEET_REFS}" (at 70.485 6.35 0)
      (effects (font (size 1.27 1.27)) hide)
    )
  )
  (global_label "ROT_QSPI_SCK" (shape input) (at 264.16 90.17 180) (fields_autoplaced)
    (effects (font (size 1.27 1.27)) (justify right))
    (property "Intersheetrefs" "${INTERSHEET_REFS}" (at 55.245 -45.085 0)
      (effects (font (size 1.27 1.27)) hide)
    )
  )
  (global_label "QSPIA2_D2" (shape input) (at 300.99 115.57 0) (fields_autoplaced)
    (effects (font (size 1.27 1.27)) (justify left))
    (property "Intersheetrefs" "${INTERSHEET_REFS}" (at 55.245 -45.085 0)
      (effects (font (size 1.27 1.27)) hide)
    )
  )
  (global_label "QSPIA2_CS_N" (shape input) (at 118.11 134.62 180) (fields_autoplaced)
    (effects (font (size 1.27 1.27)) (justify right))
    (property "Intersheetrefs" "${INTERSHEET_REFS}" (at 69.215 17.78 0)
      (effects (font (size 1.27 1.27)) hide)
    )
  )
  (global_label "GPIO" (shape input) (at 293.37 214.63 0) (fields_autoplaced)
    (effects (font (size 1.27 1.27)) (justify left))
    (property "Intersheetrefs" "${INTERSHEET_REFS}" (at -9.525 158.75 0)
      (effects (font (size 1.27 1.27)) hide)
    )
  )
  (global_label "QSPIA1_D3" (shape input) (at 118.11 69.85 180) (fields_autoplaced)
    (effects (font (size 1.27 1.27)) (justify right))
    (property "Intersheetrefs" "${INTERSHEET_REFS}" (at 68.58 -5.08 0)
      (effects (font (size 1.27 1.27)) hide)
    )
  )
  (global_label "QSPIB2_D2" (shape input) (at 300.99 87.63 0) (fields_autoplaced)
    (effects (font (size 1.27 1.27)) (justify left))
    (property "Intersheetrefs" "${INTERSHEET_REFS}" (at 55.245 -45.085 0)
      (effects (font (size 1.27 1.27)) hide)
    )
  )
  (global_label "QSPIB1_D1" (shape input) (at 300.99 97.79 0) (fields_autoplaced)
    (effects (font (size 1.27 1.27)) (justify left))
    (property "Intersheetrefs" "${INTERSHEET_REFS}" (at 55.245 -45.085 0)
      (effects (font (size 1.27 1.27)) hide)
    )
  )

  (symbol (lib_id "antmicroResistors0402:R_4k7_0402") (at 139.7 48.26 270) (unit 1)
    (in_bom yes) (on_board yes) (dnp no)
    (property "Reference" "R24" (at 138.43 48.26 0)
      (effects (font (size 1.524 1.524)) (justify right))
    )
    (property "Value" "R_4k7_0402" (at 135.89 48.26 0)
      (effects (font (size 1.524 1.524)) hide)
    )
    (property "Footprint" "antmicro-footprints:R_0402_1005Metric" (at 144.78 53.34 0)
      (effects (font (size 1.524 1.524)) (justify left) hide)
    )
    (property "Datasheet" "https://www.bourns.com/docs/product-datasheets/cr.pdf" (at 139.7 48.26 0)
      (effects (font (size 1.27 1.27)) hide)
    )
    (property "Manufacturer" "Bourns" (at 149.86 53.34 0)
      (effects (font (size 1.524 1.524)) (justify left) hide)
    )
    (property "MPN" "CR0402-FX-4701GLF" (at 147.32 53.34 0)
      (effects (font (size 1.524 1.524)) (justify left) hide)
    )
    (property "Val" "4k7" (at 138.43 57.15 0)
      (effects (font (size 1.27 1.27)) (justify right))
    )
    (property "License" "Apache-2.0" (at 114.3 68.58 0)
      (effects (font (size 1.27 1.27) (thickness 0.15)) (justify left bottom) hide)
    )
    (property "Author" "Antmicro" (at 111.76 68.58 0)
      (effects (font (size 1.27 1.27) (thickness 0.15)) (justify left bottom) hide)
    )
    (property "Tolerance" "1%" (at 129.54 68.58 0)
      (effects (font (size 1.27 1.27)) (justify left bottom) hide)
    )
    (property "Public" "False" (at 109.22 68.58 0)
      (effects (font (size 1.27 1.27)) (justify left bottom) hide)
    )
    (pin "1")
    (pin "2")
    (instances
      (project "ecp5-dc-scm"
        (path ""
          (reference "R24") (unit 1)
        )
      )
    )
  )

  (symbol (lib_id "antmicroResistors0402:R_1k_0402") (at 135.89 48.26 270) (unit 1)
    (in_bom yes) (on_board yes) (dnp no)
    (property "Reference" "R28" (at 134.62 43.18 0)
      (effects (font (size 1.524 1.524)) (justify left))
    )
    (property "Value" "R_1k_0402" (at 132.08 48.26 0)
      (effects (font (size 1.524 1.524)) hide)
    )
    (property "Footprint" "antmicro-footprints:R_0402_1005Metric" (at 140.97 53.34 0)
      (effects (font (size 1.524 1.524)) (justify left) hide)
    )
    (property "Datasheet" "https://www.bourns.com/docs/product-datasheets/cr.pdf" (at 135.89 48.26 0)
      (effects (font (size 1.27 1.27)) hide)
    )
    (property "Manufacturer" "Bourns" (at 146.05 53.34 0)
      (effects (font (size 1.524 1.524)) (justify left) hide)
    )
    (property "MPN" "CR0402-FX-1001GLF" (at 143.51 53.34 0)
      (effects (font (size 1.524 1.524)) (justify left) hide)
    )
    (property "Val" "1k" (at 134.62 53.34 0)
      (effects (font (size 1.27 1.27)) (justify left))
    )
    (property "License" "Apache-2.0" (at 110.49 68.58 0)
      (effects (font (size 1.27 1.27) (thickness 0.15)) (justify left bottom) hide)
    )
    (property "Author" "Antmicro" (at 107.95 68.58 0)
      (effects (font (size 1.27 1.27) (thickness 0.15)) (justify left bottom) hide)
    )
    (property "Tolerance" "1%" (at 125.73 68.58 0)
      (effects (font (size 1.27 1.27)) (justify left bottom) hide)
    )
    (property "Public" "False" (at 105.41 68.58 0)
      (effects (font (size 1.27 1.27)) (justify left bottom) hide)
    )
    (pin "1")
    (pin "2")
    (instances
      (project "ecp5-dc-scm"
        (path ""
          (reference "R28") (unit 1)
        )
      )
    )
  )

  (symbol (lib_id "antmicroResistors0402:R_10k_0402") (at 120.65 53.34 90) (unit 1)
    (in_bom yes) (on_board yes) (dnp no)
    (property "Reference" "R32" (at 119.38 43.18 0)
      (effects (font (size 1.524 1.524)) (justify right))
    )
    (property "Value" "R_10k_0402" (at 124.46 53.34 0)
      (effects (font (size 1.524 1.524)) hide)
    )
    (property "Footprint" "antmicro-footprints:R_0402_1005Metric" (at 115.57 48.26 0)
      (effects (font (size 1.524 1.524)) (justify left) hide)
    )
    (property "Datasheet" "https://www.bourns.com/docs/product-datasheets/cr.pdf" (at 120.65 53.34 0)
      (effects (font (size 1.27 1.27)) hide)
    )
    (property "Manufacturer" "Bourns" (at 110.49 48.26 0)
      (effects (font (size 1.524 1.524)) (justify left) hide)
    )
    (property "MPN" "CR0402-FX-1002GLF" (at 113.03 48.26 0)
      (effects (font (size 1.524 1.524)) (justify left) hide)
    )
    (property "Val" "10k" (at 119.38 53.34 0)
      (effects (font (size 1.27 1.27)) (justify right))
    )
    (property "License" "Apache-2.0" (at 146.05 33.02 0)
      (effects (font (size 1.27 1.27) (thickness 0.15)) (justify left bottom) hide)
    )
    (property "Author" "Antmicro" (at 148.59 33.02 0)
      (effects (font (size 1.27 1.27) (thickness 0.15)) (justify left bottom) hide)
    )
    (property "Tolerance" "1%" (at 130.81 33.02 0)
      (effects (font (size 1.27 1.27)) (justify left bottom) hide)
    )
    (property "Public" "False" (at 151.13 33.02 0)
      (effects (font (size 1.27 1.27)) (justify left bottom) hide)
    )
    (pin "1")
    (pin "2")
    (instances
      (project "ecp5-dc-scm"
        (path ""
          (reference "R32") (unit 1)
        )
      )
    )
  )

  (symbol (lib_id "antmicroResistors0402:R_10k_0402") (at 132.08 53.34 90) (unit 1)
    (in_bom yes) (on_board yes) (dnp no)
    (property "Reference" "R40" (at 130.81 43.18 0)
      (effects (font (size 1.524 1.524)) (justify right))
    )
    (property "Value" "R_10k_0402" (at 135.89 53.34 0)
      (effects (font (size 1.524 1.524)) hide)
    )
    (property "Footprint" "antmicro-footprints:R_0402_1005Metric" (at 127 48.26 0)
      (effects (font (size 1.524 1.524)) (justify left) hide)
    )
    (property "Datasheet" "https://www.bourns.com/docs/product-datasheets/cr.pdf" (at 132.08 53.34 0)
      (effects (font (size 1.27 1.27)) hide)
    )
    (property "Manufacturer" "Bourns" (at 121.92 48.26 0)
      (effects (font (size 1.524 1.524)) (justify left) hide)
    )
    (property "MPN" "CR0402-FX-1002GLF" (at 124.46 48.26 0)
      (effects (font (size 1.524 1.524)) (justify left) hide)
    )
    (property "Val" "10k" (at 130.81 53.34 0)
      (effects (font (size 1.27 1.27)) (justify right))
    )
    (property "License" "Apache-2.0" (at 157.48 33.02 0)
      (effects (font (size 1.27 1.27) (thickness 0.15)) (justify left bottom) hide)
    )
    (property "Author" "Antmicro" (at 160.02 33.02 0)
      (effects (font (size 1.27 1.27) (thickness 0.15)) (justify left bottom) hide)
    )
    (property "Tolerance" "1%" (at 142.24 33.02 0)
      (effects (font (size 1.27 1.27)) (justify left bottom) hide)
    )
    (property "Public" "False" (at 162.56 33.02 0)
      (effects (font (size 1.27 1.27)) (justify left bottom) hide)
    )
    (pin "1")
    (pin "2")
    (instances
      (project "ecp5-dc-scm"
        (path ""
          (reference "R40") (unit 1)
        )
      )
    )
  )

  (symbol (lib_id "antmicroResistors0402:R_10k_0402") (at 124.46 53.34 90) (unit 1)
    (in_bom yes) (on_board yes) (dnp no)
    (property "Reference" "R44" (at 122.555 43.18 0)
      (effects (font (size 1.524 1.524)) (justify right))
    )
    (property "Value" "R_10k_0402" (at 128.27 53.34 0)
      (effects (font (size 1.524 1.524)) hide)
    )
    (property "Footprint" "antmicro-footprints:R_0402_1005Metric" (at 119.38 48.26 0)
      (effects (font (size 1.524 1.524)) (justify left) hide)
    )
    (property "Datasheet" "https://www.bourns.com/docs/product-datasheets/cr.pdf" (at 124.46 53.34 0)
      (effects (font (size 1.27 1.27)) hide)
    )
    (property "Manufacturer" "Bourns" (at 114.3 48.26 0)
      (effects (font (size 1.524 1.524)) (justify left) hide)
    )
    (property "MPN" "CR0402-FX-1002GLF" (at 116.84 48.26 0)
      (effects (font (size 1.524 1.524)) (justify left) hide)
    )
    (property "Val" "10k" (at 123.19 53.34 0)
      (effects (font (size 1.27 1.27)) (justify right))
    )
    (property "License" "Apache-2.0" (at 149.86 33.02 0)
      (effects (font (size 1.27 1.27) (thickness 0.15)) (justify left bottom) hide)
    )
    (property "Author" "Antmicro" (at 152.4 33.02 0)
      (effects (font (size 1.27 1.27) (thickness 0.15)) (justify left bottom) hide)
    )
    (property "Tolerance" "1%" (at 134.62 33.02 0)
      (effects (font (size 1.27 1.27)) (justify left bottom) hide)
    )
    (property "Public" "False" (at 154.94 33.02 0)
      (effects (font (size 1.27 1.27)) (justify left bottom) hide)
    )
    (pin "1")
    (pin "2")
    (instances
      (project "ecp5-dc-scm"
        (path ""
          (reference "R44") (unit 1)
        )
      )
    )
  )

  (symbol (lib_id "antmicroCapacitors0402:C_470n_0402") (at 170.18 69.85 90) (unit 1)
    (in_bom yes) (on_board yes) (dnp no) (fields_autoplaced)
    (property "Reference" "C46" (at 172.72 66.0336 90)
      (effects (font (size 1.524 1.524)) (justify right))
    )
    (property "Value" "C_470n_0402" (at 173.99 69.85 0)
      (effects (font (size 1.524 1.524)) hide)
    )
    (property "Footprint" "antmicro-footprints:C_0402_1005Metric" (at 165.1 64.77 0)
      (effects (font (size 1.524 1.524)) (justify left) hide)
    )
    (property "Datasheet" "https://product.tdk.com/en/search/capacitor/ceramic/mlcc/info?part_no=C1005X5R1E474M050BB" (at 170.18 69.85 0)
      (effects (font (size 1.27 1.27)) hide)
    )
    (property "Manufacturer" "TDK" (at 160.02 64.77 0)
      (effects (font (size 1.524 1.524)) (justify left) hide)
    )
    (property "MPN" "C1005X5R1E474M050BB" (at 162.56 64.77 0)
      (effects (font (size 1.524 1.524)) (justify left) hide)
    )
    (property "Val" "470n" (at 172.72 68.5736 90)
      (effects (font (size 1.27 1.27)) (justify right))
    )
    (property "License" "Apache-2.0" (at 193.04 49.53 0)
      (effects (font (size 1.27 1.27) (thickness 0.15)) (justify left bottom) hide)
    )
    (property "Author" "Antmicro" (at 195.58 49.53 0)
      (effects (font (size 1.27 1.27) (thickness 0.15)) (justify left bottom) hide)
    )
    (property "Voltage" "" (at 198.12 49.53 0)
      (effects (font (size 1.27 1.27)) (justify left bottom) hide)
    )
    (property "Dielectric" "" (at 200.66 49.53 0)
      (effects (font (size 1.27 1.27)) (justify left bottom) hide)
    )
    (property "Public" "False" (at 203.2 49.53 0)
      (effects (font (size 1.27 1.27)) (justify left bottom) hide)
    )
    (pin "1")
    (pin "2")
    (instances
      (project "ecp5-dc-scm"
        (path ""
          (reference "C46") (unit 1)
        )
      )
    )
  )

  (symbol (lib_id "antmicropower:GND") (at 170.18 76.2 0) (unit 1)
    (in_bom yes) (on_board yes) (dnp no)
    (property "Reference" "#PWR019" (at 170.18 82.55 0)
      (effects (font (size 1.27 1.27)) hide)
    )
    (property "Value" "GND" (at 170.307 80.5942 0)
      (effects (font (size 1.27 1.27)))
    )
    (property "Footprint" "" (at 170.18 76.2 0)
      (effects (font (size 1.27 1.27)) hide)
    )
    (property "Datasheet" "" (at 170.18 76.2 0)
      (effects (font (size 1.27 1.27)) hide)
    )
    (property "Author" "Antmicro" (at 179.07 83.82 0)
      (effects (font (size 1.27 1.27) (thickness 0.15)) (justify left bottom) hide)
    )
    (property "License" "Apache-2.0" (at 179.07 86.36 0)
      (effects (font (size 1.27 1.27) (thickness 0.15)) (justify left bottom) hide)
    )
    (pin "1")
    (instances
      (project "ecp5-dc-scm"
        (path ""
          (reference "#PWR019") (unit 1)
        )
      )
    )
  )

  (symbol (lib_id "antmicroResistors0402:R_10k_0402") (at 128.27 53.34 90) (unit 1)
    (in_bom yes) (on_board yes) (dnp no)
    (property "Reference" "R36" (at 127 43.18 0)
      (effects (font (size 1.524 1.524)) (justify right))
    )
    (property "Value" "R_10k_0402" (at 132.08 53.34 0)
      (effects (font (size 1.524 1.524)) hide)
    )
    (property "Footprint" "antmicro-footprints:R_0402_1005Metric" (at 123.19 48.26 0)
      (effects (font (size 1.524 1.524)) (justify left) hide)
    )
    (property "Datasheet" "https://www.bourns.com/docs/product-datasheets/cr.pdf" (at 128.27 53.34 0)
      (effects (font (size 1.27 1.27)) hide)
    )
    (property "Manufacturer" "Bourns" (at 118.11 48.26 0)
      (effects (font (size 1.524 1.524)) (justify left) hide)
    )
    (property "MPN" "CR0402-FX-1002GLF" (at 120.65 48.26 0)
      (effects (font (size 1.524 1.524)) (justify left) hide)
    )
    (property "Val" "10k" (at 127 53.34 0)
      (effects (font (size 1.27 1.27)) (justify right))
    )
    (property "License" "Apache-2.0" (at 153.67 33.02 0)
      (effects (font (size 1.27 1.27) (thickness 0.15)) (justify left bottom) hide)
    )
    (property "Author" "Antmicro" (at 156.21 33.02 0)
      (effects (font (size 1.27 1.27) (thickness 0.15)) (justify left bottom) hide)
    )
    (property "Tolerance" "1%" (at 138.43 33.02 0)
      (effects (font (size 1.27 1.27)) (justify left bottom) hide)
    )
    (property "Public" "False" (at 158.75 33.02 0)
      (effects (font (size 1.27 1.27)) (justify left bottom) hide)
    )
    (pin "1")
    (pin "2")
    (instances
      (project "ecp5-dc-scm"
        (path ""
          (reference "R36") (unit 1)
        )
      )
    )
  )

  (symbol (lib_id "antmicropower:GND") (at 279.4 226.06 0) (unit 1)
    (in_bom yes) (on_board yes) (dnp no)
    (property "Reference" "#PWR025" (at 279.4 232.41 0)
      (effects (font (size 1.27 1.27)) hide)
    )
    (property "Value" "GND" (at 279.527 230.4542 0)
      (effects (font (size 1.27 1.27)))
    )
    (property "Footprint" "" (at 279.4 226.06 0)
      (effects (font (size 1.27 1.27)) hide)
    )
    (property "Datasheet" "" (at 279.4 226.06 0)
      (effects (font (size 1.27 1.27)) hide)
    )
    (property "Author" "Antmicro" (at 288.29 233.68 0)
      (effects (font (size 1.27 1.27) (thickness 0.15)) (justify left bottom) hide)
    )
    (property "License" "Apache-2.0" (at 288.29 236.22 0)
      (effects (font (size 1.27 1.27) (thickness 0.15)) (justify left bottom) hide)
    )
    (pin "1")
    (instances
      (project "ecp5-dc-scm"
        (path ""
          (reference "#PWR025") (unit 1)
        )
      )
    )
  )

  (symbol (lib_id "antmicropower:GND") (at 292.1 226.06 0) (unit 1)
    (in_bom yes) (on_board yes) (dnp no)
    (property "Reference" "#PWR026" (at 292.1 232.41 0)
      (effects (font (size 1.27 1.27)) hide)
    )
    (property "Value" "GND" (at 292.227 230.4542 0)
      (effects (font (size 1.27 1.27)))
    )
    (property "Footprint" "" (at 292.1 226.06 0)
      (effects (font (size 1.27 1.27)) hide)
    )
    (property "Datasheet" "" (at 292.1 226.06 0)
      (effects (font (size 1.27 1.27)) hide)
    )
    (property "Author" "Antmicro" (at 300.99 233.68 0)
      (effects (font (size 1.27 1.27) (thickness 0.15)) (justify left bottom) hide)
    )
    (property "License" "Apache-2.0" (at 300.99 236.22 0)
      (effects (font (size 1.27 1.27) (thickness 0.15)) (justify left bottom) hide)
    )
    (pin "1")
    (instances
      (project "ecp5-dc-scm"
        (path ""
          (reference "#PWR026") (unit 1)
        )
      )
    )
  )

  (symbol (lib_id "antmicroResistors0402:R_4k7_0402") (at 139.7 107.95 270) (unit 1)
    (in_bom yes) (on_board yes) (dnp no)
    (property "Reference" "R23" (at 138.43 107.95 0)
      (effects (font (size 1.524 1.524)) (justify right))
    )
    (property "Value" "R_4k7_0402" (at 135.89 107.95 0)
      (effects (font (size 1.524 1.524)) hide)
    )
    (property "Footprint" "antmicro-footprints:R_0402_1005Metric" (at 144.78 113.03 0)
      (effects (font (size 1.524 1.524)) (justify left) hide)
    )
    (property "Datasheet" "https://www.bourns.com/docs/product-datasheets/cr.pdf" (at 139.7 107.95 0)
      (effects (font (size 1.27 1.27)) hide)
    )
    (property "Manufacturer" "Bourns" (at 149.86 113.03 0)
      (effects (font (size 1.524 1.524)) (justify left) hide)
    )
    (property "MPN" "CR0402-FX-4701GLF" (at 147.32 113.03 0)
      (effects (font (size 1.524 1.524)) (justify left) hide)
    )
    (property "Val" "4k7" (at 138.43 116.84 0)
      (effects (font (size 1.27 1.27)) (justify right))
    )
    (property "License" "Apache-2.0" (at 114.3 128.27 0)
      (effects (font (size 1.27 1.27) (thickness 0.15)) (justify left bottom) hide)
    )
    (property "Author" "Antmicro" (at 111.76 128.27 0)
      (effects (font (size 1.27 1.27) (thickness 0.15)) (justify left bottom) hide)
    )
    (property "Tolerance" "1%" (at 129.54 128.27 0)
      (effects (font (size 1.27 1.27)) (justify left bottom) hide)
    )
    (property "Public" "False" (at 109.22 128.27 0)
      (effects (font (size 1.27 1.27)) (justify left bottom) hide)
    )
    (pin "1")
    (pin "2")
    (instances
      (project "ecp5-dc-scm"
        (path ""
          (reference "R23") (unit 1)
        )
      )
    )
  )

  (symbol (lib_id "antmicroResistors0402:R_1k_0402") (at 135.89 107.95 270) (unit 1)
    (in_bom yes) (on_board yes) (dnp no)
    (property "Reference" "R27" (at 134.62 102.87 0)
      (effects (font (size 1.524 1.524)) (justify left))
    )
    (property "Value" "R_1k_0402" (at 132.08 107.95 0)
      (effects (font (size 1.524 1.524)) hide)
    )
    (property "Footprint" "antmicro-footprints:R_0402_1005Metric" (at 140.97 113.03 0)
      (effects (font (size 1.524 1.524)) (justify left) hide)
    )
    (property "Datasheet" "https://www.bourns.com/docs/product-datasheets/cr.pdf" (at 135.89 107.95 0)
      (effects (font (size 1.27 1.27)) hide)
    )
    (property "Manufacturer" "Bourns" (at 146.05 113.03 0)
      (effects (font (size 1.524 1.524)) (justify left) hide)
    )
    (property "MPN" "CR0402-FX-1001GLF" (at 143.51 113.03 0)
      (effects (font (size 1.524 1.524)) (justify left) hide)
    )
    (property "Val" "1k" (at 134.62 113.03 0)
      (effects (font (size 1.27 1.27)) (justify left))
    )
    (property "License" "Apache-2.0" (at 110.49 128.27 0)
      (effects (font (size 1.27 1.27) (thickness 0.15)) (justify left bottom) hide)
    )
    (property "Author" "Antmicro" (at 107.95 128.27 0)
      (effects (font (size 1.27 1.27) (thickness 0.15)) (justify left bottom) hide)
    )
    (property "Tolerance" "1%" (at 125.73 128.27 0)
      (effects (font (size 1.27 1.27)) (justify left bottom) hide)
    )
    (property "Public" "False" (at 105.41 128.27 0)
      (effects (font (size 1.27 1.27)) (justify left bottom) hide)
    )
    (pin "1")
    (pin "2")
    (instances
      (project "ecp5-dc-scm"
        (path ""
          (reference "R27") (unit 1)
        )
      )
    )
  )

  (symbol (lib_id "antmicroResistors0402:R_10k_0402") (at 120.65 113.03 90) (unit 1)
    (in_bom yes) (on_board yes) (dnp no)
    (property "Reference" "R31" (at 119.38 102.87 0)
      (effects (font (size 1.524 1.524)) (justify right))
    )
    (property "Value" "R_10k_0402" (at 124.46 113.03 0)
      (effects (font (size 1.524 1.524)) hide)
    )
    (property "Footprint" "antmicro-footprints:R_0402_1005Metric" (at 115.57 107.95 0)
      (effects (font (size 1.524 1.524)) (justify left) hide)
    )
    (property "Datasheet" "https://www.bourns.com/docs/product-datasheets/cr.pdf" (at 120.65 113.03 0)
      (effects (font (size 1.27 1.27)) hide)
    )
    (property "Manufacturer" "Bourns" (at 110.49 107.95 0)
      (effects (font (size 1.524 1.524)) (justify left) hide)
    )
    (property "MPN" "CR0402-FX-1002GLF" (at 113.03 107.95 0)
      (effects (font (size 1.524 1.524)) (justify left) hide)
    )
    (property "Val" "10k" (at 119.38 113.03 0)
      (effects (font (size 1.27 1.27)) (justify right))
    )
    (property "License" "Apache-2.0" (at 146.05 92.71 0)
      (effects (font (size 1.27 1.27) (thickness 0.15)) (justify left bottom) hide)
    )
    (property "Author" "Antmicro" (at 148.59 92.71 0)
      (effects (font (size 1.27 1.27) (thickness 0.15)) (justify left bottom) hide)
    )
    (property "Tolerance" "1%" (at 130.81 92.71 0)
      (effects (font (size 1.27 1.27)) (justify left bottom) hide)
    )
    (property "Public" "False" (at 151.13 92.71 0)
      (effects (font (size 1.27 1.27)) (justify left bottom) hide)
    )
    (pin "1")
    (pin "2")
    (instances
      (project "ecp5-dc-scm"
        (path ""
          (reference "R31") (unit 1)
        )
      )
    )
  )

  (symbol (lib_id "antmicroResistors0402:R_10k_0402") (at 132.08 113.03 90) (unit 1)
    (in_bom yes) (on_board yes) (dnp no)
    (property "Reference" "R39" (at 130.81 102.87 0)
      (effects (font (size 1.524 1.524)) (justify right))
    )
    (property "Value" "R_10k_0402" (at 135.89 113.03 0)
      (effects (font (size 1.524 1.524)) hide)
    )
    (property "Footprint" "antmicro-footprints:R_0402_1005Metric" (at 127 107.95 0)
      (effects (font (size 1.524 1.524)) (justify left) hide)
    )
    (property "Datasheet" "https://www.bourns.com/docs/product-datasheets/cr.pdf" (at 132.08 113.03 0)
      (effects (font (size 1.27 1.27)) hide)
    )
    (property "Manufacturer" "Bourns" (at 121.92 107.95 0)
      (effects (font (size 1.524 1.524)) (justify left) hide)
    )
    (property "MPN" "CR0402-FX-1002GLF" (at 124.46 107.95 0)
      (effects (font (size 1.524 1.524)) (justify left) hide)
    )
    (property "Val" "10k" (at 130.81 113.03 0)
      (effects (font (size 1.27 1.27)) (justify right))
    )
    (property "License" "Apache-2.0" (at 157.48 92.71 0)
      (effects (font (size 1.27 1.27) (thickness 0.15)) (justify left bottom) hide)
    )
    (property "Author" "Antmicro" (at 160.02 92.71 0)
      (effects (font (size 1.27 1.27) (thickness 0.15)) (justify left bottom) hide)
    )
    (property "Tolerance" "1%" (at 142.24 92.71 0)
      (effects (font (size 1.27 1.27)) (justify left bottom) hide)
    )
    (property "Public" "False" (at 162.56 92.71 0)
      (effects (font (size 1.27 1.27)) (justify left bottom) hide)
    )
    (pin "1")
    (pin "2")
    (instances
      (project "ecp5-dc-scm"
        (path ""
          (reference "R39") (unit 1)
        )
      )
    )
  )

  (symbol (lib_id "antmicroResistors0402:R_10k_0402") (at 124.46 113.03 90) (unit 1)
    (in_bom yes) (on_board yes) (dnp no)
    (property "Reference" "R43" (at 123.19 102.87 0)
      (effects (font (size 1.524 1.524)) (justify right))
    )
    (property "Value" "R_10k_0402" (at 128.27 113.03 0)
      (effects (font (size 1.524 1.524)) hide)
    )
    (property "Footprint" "antmicro-footprints:R_0402_1005Metric" (at 119.38 107.95 0)
      (effects (font (size 1.524 1.524)) (justify left) hide)
    )
    (property "Datasheet" "https://www.bourns.com/docs/product-datasheets/cr.pdf" (at 124.46 113.03 0)
      (effects (font (size 1.27 1.27)) hide)
    )
    (property "Manufacturer" "Bourns" (at 114.3 107.95 0)
      (effects (font (size 1.524 1.524)) (justify left) hide)
    )
    (property "MPN" "CR0402-FX-1002GLF" (at 116.84 107.95 0)
      (effects (font (size 1.524 1.524)) (justify left) hide)
    )
    (property "Val" "10k" (at 123.19 113.03 0)
      (effects (font (size 1.27 1.27)) (justify right))
    )
    (property "License" "Apache-2.0" (at 149.86 92.71 0)
      (effects (font (size 1.27 1.27) (thickness 0.15)) (justify left bottom) hide)
    )
    (property "Author" "Antmicro" (at 152.4 92.71 0)
      (effects (font (size 1.27 1.27) (thickness 0.15)) (justify left bottom) hide)
    )
    (property "Tolerance" "1%" (at 134.62 92.71 0)
      (effects (font (size 1.27 1.27)) (justify left bottom) hide)
    )
    (property "Public" "False" (at 154.94 92.71 0)
      (effects (font (size 1.27 1.27)) (justify left bottom) hide)
    )
    (pin "1")
    (pin "2")
    (instances
      (project "ecp5-dc-scm"
        (path ""
          (reference "R43") (unit 1)
        )
      )
    )
  )

  (symbol (lib_id "antmicroCapacitors0402:C_470n_0402") (at 172.72 130.81 90) (unit 1)
    (in_bom yes) (on_board yes) (dnp no) (fields_autoplaced)
    (property "Reference" "C45" (at 175.26 126.9936 90)
      (effects (font (size 1.524 1.524)) (justify right))
    )
    (property "Value" "C_470n_0402" (at 176.53 130.81 0)
      (effects (font (size 1.524 1.524)) hide)
    )
    (property "Footprint" "antmicro-footprints:C_0402_1005Metric" (at 167.64 125.73 0)
      (effects (font (size 1.524 1.524)) (justify left) hide)
    )
    (property "Datasheet" "https://product.tdk.com/en/search/capacitor/ceramic/mlcc/info?part_no=C1005X5R1E474M050BB" (at 172.72 130.81 0)
      (effects (font (size 1.27 1.27)) hide)
    )
    (property "Manufacturer" "TDK" (at 162.56 125.73 0)
      (effects (font (size 1.524 1.524)) (justify left) hide)
    )
    (property "MPN" "C1005X5R1E474M050BB" (at 165.1 125.73 0)
      (effects (font (size 1.524 1.524)) (justify left) hide)
    )
    (property "Val" "470n" (at 175.26 129.5336 90)
      (effects (font (size 1.27 1.27)) (justify right))
    )
    (property "License" "Apache-2.0" (at 195.58 110.49 0)
      (effects (font (size 1.27 1.27) (thickness 0.15)) (justify left bottom) hide)
    )
    (property "Author" "Antmicro" (at 198.12 110.49 0)
      (effects (font (size 1.27 1.27) (thickness 0.15)) (justify left bottom) hide)
    )
    (property "Voltage" "" (at 200.66 110.49 0)
      (effects (font (size 1.27 1.27)) (justify left bottom) hide)
    )
    (property "Dielectric" "" (at 203.2 110.49 0)
      (effects (font (size 1.27 1.27)) (justify left bottom) hide)
    )
    (property "Public" "False" (at 205.74 110.49 0)
      (effects (font (size 1.27 1.27)) (justify left bottom) hide)
    )
    (pin "1")
    (pin "2")
    (instances
      (project "ecp5-dc-scm"
        (path ""
          (reference "C45") (unit 1)
        )
      )
    )
  )

  (symbol (lib_id "antmicropower:GND") (at 172.72 137.16 0) (unit 1)
    (in_bom yes) (on_board yes) (dnp no)
    (property "Reference" "#PWR018" (at 172.72 143.51 0)
      (effects (font (size 1.27 1.27)) hide)
    )
    (property "Value" "GND" (at 172.847 141.5542 0)
      (effects (font (size 1.27 1.27)))
    )
    (property "Footprint" "" (at 172.72 137.16 0)
      (effects (font (size 1.27 1.27)) hide)
    )
    (property "Datasheet" "" (at 172.72 137.16 0)
      (effects (font (size 1.27 1.27)) hide)
    )
    (property "Author" "Antmicro" (at 181.61 144.78 0)
      (effects (font (size 1.27 1.27) (thickness 0.15)) (justify left bottom) hide)
    )
    (property "License" "Apache-2.0" (at 181.61 147.32 0)
      (effects (font (size 1.27 1.27) (thickness 0.15)) (justify left bottom) hide)
    )
    (pin "1")
    (instances
      (project "ecp5-dc-scm"
        (path ""
          (reference "#PWR018") (unit 1)
        )
      )
    )
  )

  (symbol (lib_id "antmicroResistors0402:R_10k_0402") (at 128.27 113.03 90) (unit 1)
    (in_bom yes) (on_board yes) (dnp no)
    (property "Reference" "R35" (at 127 102.87 0)
      (effects (font (size 1.524 1.524)) (justify right))
    )
    (property "Value" "R_10k_0402" (at 132.08 113.03 0)
      (effects (font (size 1.524 1.524)) hide)
    )
    (property "Footprint" "antmicro-footprints:R_0402_1005Metric" (at 123.19 107.95 0)
      (effects (font (size 1.524 1.524)) (justify left) hide)
    )
    (property "Datasheet" "https://www.bourns.com/docs/product-datasheets/cr.pdf" (at 128.27 113.03 0)
      (effects (font (size 1.27 1.27)) hide)
    )
    (property "Manufacturer" "Bourns" (at 118.11 107.95 0)
      (effects (font (size 1.524 1.524)) (justify left) hide)
    )
    (property "MPN" "CR0402-FX-1002GLF" (at 120.65 107.95 0)
      (effects (font (size 1.524 1.524)) (justify left) hide)
    )
    (property "Val" "10k" (at 127 113.03 0)
      (effects (font (size 1.27 1.27)) (justify right))
    )
    (property "License" "Apache-2.0" (at 153.67 92.71 0)
      (effects (font (size 1.27 1.27) (thickness 0.15)) (justify left bottom) hide)
    )
    (property "Author" "Antmicro" (at 156.21 92.71 0)
      (effects (font (size 1.27 1.27) (thickness 0.15)) (justify left bottom) hide)
    )
    (property "Tolerance" "1%" (at 138.43 92.71 0)
      (effects (font (size 1.27 1.27)) (justify left bottom) hide)
    )
    (property "Public" "False" (at 158.75 92.71 0)
      (effects (font (size 1.27 1.27)) (justify left bottom) hide)
    )
    (pin "1")
    (pin "2")
    (instances
      (project "ecp5-dc-scm"
        (path ""
          (reference "R35") (unit 1)
        )
      )
    )
  )

  (symbol (lib_id "antmicroResistors0402:R_4k7_0402") (at 139.7 180.34 270) (unit 1)
    (in_bom yes) (on_board yes) (dnp no)
    (property "Reference" "R22" (at 138.43 176.53 0)
      (effects (font (size 1.524 1.524)) (justify left))
    )
    (property "Value" "R_4k7_0402" (at 135.89 180.34 0)
      (effects (font (size 1.524 1.524)) hide)
    )
    (property "Footprint" "antmicro-footprints:R_0402_1005Metric" (at 144.78 185.42 0)
      (effects (font (size 1.524 1.524)) (justify left) hide)
    )
    (property "Datasheet" "https://www.bourns.com/docs/product-datasheets/cr.pdf" (at 139.7 180.34 0)
      (effects (font (size 1.27 1.27)) hide)
    )
    (property "Manufacturer" "Bourns" (at 149.86 185.42 0)
      (effects (font (size 1.524 1.524)) (justify left) hide)
    )
    (property "MPN" "CR0402-FX-4701GLF" (at 147.32 185.42 0)
      (effects (font (size 1.524 1.524)) (justify left) hide)
    )
    (property "Val" "4k7" (at 138.43 185.42 0)
      (effects (font (size 1.27 1.27)) (justify left))
    )
    (property "License" "Apache-2.0" (at 114.3 200.66 0)
      (effects (font (size 1.27 1.27) (thickness 0.15)) (justify left bottom) hide)
    )
    (property "Author" "Antmicro" (at 111.76 200.66 0)
      (effects (font (size 1.27 1.27) (thickness 0.15)) (justify left bottom) hide)
    )
    (property "Tolerance" "1%" (at 129.54 200.66 0)
      (effects (font (size 1.27 1.27)) (justify left bottom) hide)
    )
    (property "Public" "False" (at 109.22 200.66 0)
      (effects (font (size 1.27 1.27)) (justify left bottom) hide)
    )
    (pin "1")
    (pin "2")
    (instances
      (project "ecp5-dc-scm"
        (path ""
          (reference "R22") (unit 1)
        )
      )
    )
  )

  (symbol (lib_id "antmicroResistors0402:R_1k_0402") (at 135.89 180.34 270) (unit 1)
    (in_bom yes) (on_board yes) (dnp no)
    (property "Reference" "R26" (at 134.62 176.53 0)
      (effects (font (size 1.524 1.524)) (justify left))
    )
    (property "Value" "R_1k_0402" (at 132.08 180.34 0)
      (effects (font (size 1.524 1.524)) hide)
    )
    (property "Footprint" "antmicro-footprints:R_0402_1005Metric" (at 140.97 185.42 0)
      (effects (font (size 1.524 1.524)) (justify left) hide)
    )
    (property "Datasheet" "https://www.bourns.com/docs/product-datasheets/cr.pdf" (at 135.89 180.34 0)
      (effects (font (size 1.27 1.27)) hide)
    )
    (property "Manufacturer" "Bourns" (at 146.05 185.42 0)
      (effects (font (size 1.524 1.524)) (justify left) hide)
    )
    (property "MPN" "CR0402-FX-1001GLF" (at 143.51 185.42 0)
      (effects (font (size 1.524 1.524)) (justify left) hide)
    )
    (property "Val" "1k" (at 134.62 185.42 0)
      (effects (font (size 1.27 1.27)) (justify left))
    )
    (property "License" "Apache-2.0" (at 110.49 200.66 0)
      (effects (font (size 1.27 1.27) (thickness 0.15)) (justify left bottom) hide)
    )
    (property "Author" "Antmicro" (at 107.95 200.66 0)
      (effects (font (size 1.27 1.27) (thickness 0.15)) (justify left bottom) hide)
    )
    (property "Tolerance" "1%" (at 125.73 200.66 0)
      (effects (font (size 1.27 1.27)) (justify left bottom) hide)
    )
    (property "Public" "False" (at 105.41 200.66 0)
      (effects (font (size 1.27 1.27)) (justify left bottom) hide)
    )
    (pin "1")
    (pin "2")
    (instances
      (project "ecp5-dc-scm"
        (path ""
          (reference "R26") (unit 1)
        )
      )
    )
  )

  (symbol (lib_id "antmicroResistors0402:R_10k_0402") (at 120.65 185.42 90) (unit 1)
    (in_bom yes) (on_board yes) (dnp no)
    (property "Reference" "R30" (at 119.38 176.53 0)
      (effects (font (size 1.524 1.524)) (justify right))
    )
    (property "Value" "R_10k_0402" (at 124.46 185.42 0)
      (effects (font (size 1.524 1.524)) hide)
    )
    (property "Footprint" "antmicro-footprints:R_0402_1005Metric" (at 115.57 180.34 0)
      (effects (font (size 1.524 1.524)) (justify left) hide)
    )
    (property "Datasheet" "https://www.bourns.com/docs/product-datasheets/cr.pdf" (at 120.65 185.42 0)
      (effects (font (size 1.27 1.27)) hide)
    )
    (property "Manufacturer" "Bourns" (at 110.49 180.34 0)
      (effects (font (size 1.524 1.524)) (justify left) hide)
    )
    (property "MPN" "CR0402-FX-1002GLF" (at 113.03 180.34 0)
      (effects (font (size 1.524 1.524)) (justify left) hide)
    )
    (property "Val" "10k" (at 119.38 185.42 0)
      (effects (font (size 1.27 1.27)) (justify right))
    )
    (property "License" "Apache-2.0" (at 146.05 165.1 0)
      (effects (font (size 1.27 1.27) (thickness 0.15)) (justify left bottom) hide)
    )
    (property "Author" "Antmicro" (at 148.59 165.1 0)
      (effects (font (size 1.27 1.27) (thickness 0.15)) (justify left bottom) hide)
    )
    (property "Tolerance" "1%" (at 130.81 165.1 0)
      (effects (font (size 1.27 1.27)) (justify left bottom) hide)
    )
    (property "Public" "False" (at 151.13 165.1 0)
      (effects (font (size 1.27 1.27)) (justify left bottom) hide)
    )
    (pin "1")
    (pin "2")
    (instances
      (project "ecp5-dc-scm"
        (path ""
          (reference "R30") (unit 1)
        )
      )
    )
  )

  (symbol (lib_id "antmicroResistors0402:R_10k_0402") (at 132.08 185.42 90) (unit 1)
    (in_bom yes) (on_board yes) (dnp no)
    (property "Reference" "R38" (at 130.81 176.53 0)
      (effects (font (size 1.524 1.524)) (justify right))
    )
    (property "Value" "R_10k_0402" (at 135.89 185.42 0)
      (effects (font (size 1.524 1.524)) hide)
    )
    (property "Footprint" "antmicro-footprints:R_0402_1005Metric" (at 127 180.34 0)
      (effects (font (size 1.524 1.524)) (justify left) hide)
    )
    (property "Datasheet" "https://www.bourns.com/docs/product-datasheets/cr.pdf" (at 132.08 185.42 0)
      (effects (font (size 1.27 1.27)) hide)
    )
    (property "Manufacturer" "Bourns" (at 121.92 180.34 0)
      (effects (font (size 1.524 1.524)) (justify left) hide)
    )
    (property "MPN" "CR0402-FX-1002GLF" (at 124.46 180.34 0)
      (effects (font (size 1.524 1.524)) (justify left) hide)
    )
    (property "Val" "10k" (at 130.81 185.42 0)
      (effects (font (size 1.27 1.27)) (justify right))
    )
    (property "License" "Apache-2.0" (at 157.48 165.1 0)
      (effects (font (size 1.27 1.27) (thickness 0.15)) (justify left bottom) hide)
    )
    (property "Author" "Antmicro" (at 160.02 165.1 0)
      (effects (font (size 1.27 1.27) (thickness 0.15)) (justify left bottom) hide)
    )
    (property "Tolerance" "1%" (at 142.24 165.1 0)
      (effects (font (size 1.27 1.27)) (justify left bottom) hide)
    )
    (property "Public" "False" (at 162.56 165.1 0)
      (effects (font (size 1.27 1.27)) (justify left bottom) hide)
    )
    (pin "1")
    (pin "2")
    (instances
      (project "ecp5-dc-scm"
        (path ""
          (reference "R38") (unit 1)
        )
      )
    )
  )

  (symbol (lib_id "antmicroResistors0402:R_10k_0402") (at 124.46 185.42 90) (unit 1)
    (in_bom yes) (on_board yes) (dnp no)
    (property "Reference" "R42" (at 123.19 176.53 0)
      (effects (font (size 1.524 1.524)) (justify right))
    )
    (property "Value" "R_10k_0402" (at 128.27 185.42 0)
      (effects (font (size 1.524 1.524)) hide)
    )
    (property "Footprint" "antmicro-footprints:R_0402_1005Metric" (at 119.38 180.34 0)
      (effects (font (size 1.524 1.524)) (justify left) hide)
    )
    (property "Datasheet" "https://www.bourns.com/docs/product-datasheets/cr.pdf" (at 124.46 185.42 0)
      (effects (font (size 1.27 1.27)) hide)
    )
    (property "Manufacturer" "Bourns" (at 114.3 180.34 0)
      (effects (font (size 1.524 1.524)) (justify left) hide)
    )
    (property "MPN" "CR0402-FX-1002GLF" (at 116.84 180.34 0)
      (effects (font (size 1.524 1.524)) (justify left) hide)
    )
    (property "Val" "10k" (at 123.19 185.42 0)
      (effects (font (size 1.27 1.27)) (justify right))
    )
    (property "License" "Apache-2.0" (at 149.86 165.1 0)
      (effects (font (size 1.27 1.27) (thickness 0.15)) (justify left bottom) hide)
    )
    (property "Author" "Antmicro" (at 152.4 165.1 0)
      (effects (font (size 1.27 1.27) (thickness 0.15)) (justify left bottom) hide)
    )
    (property "Tolerance" "1%" (at 134.62 165.1 0)
      (effects (font (size 1.27 1.27)) (justify left bottom) hide)
    )
    (property "Public" "False" (at 154.94 165.1 0)
      (effects (font (size 1.27 1.27)) (justify left bottom) hide)
    )
    (pin "1")
    (pin "2")
    (instances
      (project "ecp5-dc-scm"
        (path ""
          (reference "R42") (unit 1)
        )
      )
    )
  )

  (symbol (lib_id "antmicroCapacitors0402:C_470n_0402") (at 167.64 204.47 90) (unit 1)
    (in_bom yes) (on_board yes) (dnp no) (fields_autoplaced)
    (property "Reference" "C44" (at 170.18 200.6536 90)
      (effects (font (size 1.524 1.524)) (justify right))
    )
    (property "Value" "C_470n_0402" (at 171.45 204.47 0)
      (effects (font (size 1.524 1.524)) hide)
    )
    (property "Footprint" "antmicro-footprints:C_0402_1005Metric" (at 162.56 199.39 0)
      (effects (font (size 1.524 1.524)) (justify left) hide)
    )
    (property "Datasheet" "https://product.tdk.com/en/search/capacitor/ceramic/mlcc/info?part_no=C1005X5R1E474M050BB" (at 167.64 204.47 0)
      (effects (font (size 1.27 1.27)) hide)
    )
    (property "Manufacturer" "TDK" (at 157.48 199.39 0)
      (effects (font (size 1.524 1.524)) (justify left) hide)
    )
    (property "MPN" "C1005X5R1E474M050BB" (at 160.02 199.39 0)
      (effects (font (size 1.524 1.524)) (justify left) hide)
    )
    (property "Val" "470n" (at 170.18 203.1936 90)
      (effects (font (size 1.27 1.27)) (justify right))
    )
    (property "License" "Apache-2.0" (at 190.5 184.15 0)
      (effects (font (size 1.27 1.27) (thickness 0.15)) (justify left bottom) hide)
    )
    (property "Author" "Antmicro" (at 193.04 184.15 0)
      (effects (font (size 1.27 1.27) (thickness 0.15)) (justify left bottom) hide)
    )
    (property "Voltage" "" (at 195.58 184.15 0)
      (effects (font (size 1.27 1.27)) (justify left bottom) hide)
    )
    (property "Dielectric" "" (at 198.12 184.15 0)
      (effects (font (size 1.27 1.27)) (justify left bottom) hide)
    )
    (property "Public" "False" (at 200.66 184.15 0)
      (effects (font (size 1.27 1.27)) (justify left bottom) hide)
    )
    (pin "1")
    (pin "2")
    (instances
      (project "ecp5-dc-scm"
        (path ""
          (reference "C44") (unit 1)
        )
      )
    )
  )

  (symbol (lib_id "antmicropower:GND") (at 167.64 208.28 0) (unit 1)
    (in_bom yes) (on_board yes) (dnp no)
    (property "Reference" "#PWR017" (at 167.64 214.63 0)
      (effects (font (size 1.27 1.27)) hide)
    )
    (property "Value" "GND" (at 167.767 212.6742 0)
      (effects (font (size 1.27 1.27)))
    )
    (property "Footprint" "" (at 167.64 208.28 0)
      (effects (font (size 1.27 1.27)) hide)
    )
    (property "Datasheet" "" (at 167.64 208.28 0)
      (effects (font (size 1.27 1.27)) hide)
    )
    (property "Author" "Antmicro" (at 176.53 215.9 0)
      (effects (font (size 1.27 1.27) (thickness 0.15)) (justify left bottom) hide)
    )
    (property "License" "Apache-2.0" (at 176.53 218.44 0)
      (effects (font (size 1.27 1.27) (thickness 0.15)) (justify left bottom) hide)
    )
    (pin "1")
    (instances
      (project "ecp5-dc-scm"
        (path ""
          (reference "#PWR017") (unit 1)
        )
      )
    )
  )

  (symbol (lib_id "antmicroResistors0402:R_10k_0402") (at 128.27 185.42 90) (unit 1)
    (in_bom yes) (on_board yes) (dnp no)
    (property "Reference" "R34" (at 127 176.53 0)
      (effects (font (size 1.524 1.524)) (justify right))
    )
    (property "Value" "R_10k_0402" (at 132.08 185.42 0)
      (effects (font (size 1.524 1.524)) hide)
    )
    (property "Footprint" "antmicro-footprints:R_0402_1005Metric" (at 123.19 180.34 0)
      (effects (font (size 1.524 1.524)) (justify left) hide)
    )
    (property "Datasheet" "https://www.bourns.com/docs/product-datasheets/cr.pdf" (at 128.27 185.42 0)
      (effects (font (size 1.27 1.27)) hide)
    )
    (property "Manufacturer" "Bourns" (at 118.11 180.34 0)
      (effects (font (size 1.524 1.524)) (justify left) hide)
    )
    (property "MPN" "CR0402-FX-1002GLF" (at 120.65 180.34 0)
      (effects (font (size 1.524 1.524)) (justify left) hide)
    )
    (property "Val" "10k" (at 127 185.42 0)
      (effects (font (size 1.27 1.27)) (justify right))
    )
    (property "License" "Apache-2.0" (at 153.67 165.1 0)
      (effects (font (size 1.27 1.27) (thickness 0.15)) (justify left bottom) hide)
    )
    (property "Author" "Antmicro" (at 156.21 165.1 0)
      (effects (font (size 1.27 1.27) (thickness 0.15)) (justify left bottom) hide)
    )
    (property "Tolerance" "1%" (at 138.43 165.1 0)
      (effects (font (size 1.27 1.27)) (justify left bottom) hide)
    )
    (property "Public" "False" (at 158.75 165.1 0)
      (effects (font (size 1.27 1.27)) (justify left bottom) hide)
    )
    (pin "1")
    (pin "2")
    (instances
      (project "ecp5-dc-scm"
        (path ""
          (reference "R34") (unit 1)
        )
      )
    )
  )

  (symbol (lib_id "antmicroResistors0402:R_4k7_0402") (at 139.7 233.68 270) (unit 1)
    (in_bom yes) (on_board yes) (dnp no)
    (property "Reference" "R21" (at 138.43 228.6 0)
      (effects (font (size 1.524 1.524)) (justify left))
    )
    (property "Value" "R_4k7_0402" (at 135.89 233.68 0)
      (effects (font (size 1.524 1.524)) hide)
    )
    (property "Footprint" "antmicro-footprints:R_0402_1005Metric" (at 144.78 238.76 0)
      (effects (font (size 1.524 1.524)) (justify left) hide)
    )
    (property "Datasheet" "https://www.bourns.com/docs/product-datasheets/cr.pdf" (at 139.7 233.68 0)
      (effects (font (size 1.27 1.27)) hide)
    )
    (property "Manufacturer" "Bourns" (at 149.86 238.76 0)
      (effects (font (size 1.524 1.524)) (justify left) hide)
    )
    (property "MPN" "CR0402-FX-4701GLF" (at 147.32 238.76 0)
      (effects (font (size 1.524 1.524)) (justify left) hide)
    )
    (property "Val" "4k7" (at 138.43 238.76 0)
      (effects (font (size 1.27 1.27)) (justify left))
    )
    (property "License" "Apache-2.0" (at 114.3 254 0)
      (effects (font (size 1.27 1.27) (thickness 0.15)) (justify left bottom) hide)
    )
    (property "Author" "Antmicro" (at 111.76 254 0)
      (effects (font (size 1.27 1.27) (thickness 0.15)) (justify left bottom) hide)
    )
    (property "Tolerance" "1%" (at 129.54 254 0)
      (effects (font (size 1.27 1.27)) (justify left bottom) hide)
    )
    (property "Public" "False" (at 109.22 254 0)
      (effects (font (size 1.27 1.27)) (justify left bottom) hide)
    )
    (pin "1")
    (pin "2")
    (instances
      (project "ecp5-dc-scm"
        (path ""
          (reference "R21") (unit 1)
        )
      )
    )
  )

  (symbol (lib_id "antmicroResistors0402:R_1k_0402") (at 135.89 233.68 270) (unit 1)
    (in_bom yes) (on_board yes) (dnp no)
    (property "Reference" "R25" (at 134.62 228.6 0)
      (effects (font (size 1.524 1.524)) (justify left))
    )
    (property "Value" "R_1k_0402" (at 132.08 233.68 0)
      (effects (font (size 1.524 1.524)) hide)
    )
    (property "Footprint" "antmicro-footprints:R_0402_1005Metric" (at 140.97 238.76 0)
      (effects (font (size 1.524 1.524)) (justify left) hide)
    )
    (property "Datasheet" "https://www.bourns.com/docs/product-datasheets/cr.pdf" (at 135.89 233.68 0)
      (effects (font (size 1.27 1.27)) hide)
    )
    (property "Manufacturer" "Bourns" (at 146.05 238.76 0)
      (effects (font (size 1.524 1.524)) (justify left) hide)
    )
    (property "MPN" "CR0402-FX-1001GLF" (at 143.51 238.76 0)
      (effects (font (size 1.524 1.524)) (justify left) hide)
    )
    (property "Val" "1k" (at 134.62 238.76 0)
      (effects (font (size 1.27 1.27)) (justify left))
    )
    (property "License" "Apache-2.0" (at 110.49 254 0)
      (effects (font (size 1.27 1.27) (thickness 0.15)) (justify left bottom) hide)
    )
    (property "Author" "Antmicro" (at 107.95 254 0)
      (effects (font (size 1.27 1.27) (thickness 0.15)) (justify left bottom) hide)
    )
    (property "Tolerance" "1%" (at 125.73 254 0)
      (effects (font (size 1.27 1.27)) (justify left bottom) hide)
    )
    (property "Public" "False" (at 105.41 254 0)
      (effects (font (size 1.27 1.27)) (justify left bottom) hide)
    )
    (pin "1")
    (pin "2")
    (instances
      (project "ecp5-dc-scm"
        (path ""
          (reference "R25") (unit 1)
        )
      )
    )
  )

  (symbol (lib_id "antmicroResistors0402:R_10k_0402") (at 120.65 238.76 90) (unit 1)
    (in_bom yes) (on_board yes) (dnp no) (fields_autoplaced)
    (property "Reference" "R29" (at 119.38 228.6 0)
      (effects (font (size 1.524 1.524)) (justify right))
    )
    (property "Value" "R_10k_0402" (at 124.46 238.76 0)
      (effects (font (size 1.524 1.524)) hide)
    )
    (property "Footprint" "antmicro-footprints:R_0402_1005Metric" (at 115.57 233.68 0)
      (effects (font (size 1.524 1.524)) (justify left) hide)
    )
    (property "Datasheet" "https://www.bourns.com/docs/product-datasheets/cr.pdf" (at 120.65 238.76 0)
      (effects (font (size 1.27 1.27)) hide)
    )
    (property "Manufacturer" "Bourns" (at 110.49 233.68 0)
      (effects (font (size 1.524 1.524)) (justify left) hide)
    )
    (property "MPN" "CR0402-FX-1002GLF" (at 113.03 233.68 0)
      (effects (font (size 1.524 1.524)) (justify left) hide)
    )
    (property "Val" "10k" (at 119.38 238.76 0)
      (effects (font (size 1.27 1.27)) (justify right))
    )
    (property "License" "Apache-2.0" (at 146.05 218.44 0)
      (effects (font (size 1.27 1.27) (thickness 0.15)) (justify left bottom) hide)
    )
    (property "Author" "Antmicro" (at 148.59 218.44 0)
      (effects (font (size 1.27 1.27) (thickness 0.15)) (justify left bottom) hide)
    )
    (property "Tolerance" "1%" (at 130.81 218.44 0)
      (effects (font (size 1.27 1.27)) (justify left bottom) hide)
    )
    (property "Public" "False" (at 151.13 218.44 0)
      (effects (font (size 1.27 1.27)) (justify left bottom) hide)
    )
    (pin "1")
    (pin "2")
    (instances
      (project "ecp5-dc-scm"
        (path ""
          (reference "R29") (unit 1)
        )
      )
    )
  )

  (symbol (lib_id "antmicroResistors0402:R_10k_0402") (at 132.08 238.76 90) (unit 1)
    (in_bom yes) (on_board yes) (dnp no)
    (property "Reference" "R37" (at 130.81 228.6 0)
      (effects (font (size 1.524 1.524)) (justify right))
    )
    (property "Value" "R_10k_0402" (at 135.89 238.76 0)
      (effects (font (size 1.524 1.524)) hide)
    )
    (property "Footprint" "antmicro-footprints:R_0402_1005Metric" (at 127 233.68 0)
      (effects (font (size 1.524 1.524)) (justify left) hide)
    )
    (property "Datasheet" "https://www.bourns.com/docs/product-datasheets/cr.pdf" (at 132.08 238.76 0)
      (effects (font (size 1.27 1.27)) hide)
    )
    (property "Manufacturer" "Bourns" (at 121.92 233.68 0)
      (effects (font (size 1.524 1.524)) (justify left) hide)
    )
    (property "MPN" "CR0402-FX-1002GLF" (at 124.46 233.68 0)
      (effects (font (size 1.524 1.524)) (justify left) hide)
    )
    (property "Val" "10k" (at 130.81 238.76 0)
      (effects (font (size 1.27 1.27)) (justify right))
    )
    (property "License" "Apache-2.0" (at 157.48 218.44 0)
      (effects (font (size 1.27 1.27) (thickness 0.15)) (justify left bottom) hide)
    )
    (property "Author" "Antmicro" (at 160.02 218.44 0)
      (effects (font (size 1.27 1.27) (thickness 0.15)) (justify left bottom) hide)
    )
    (property "Tolerance" "1%" (at 142.24 218.44 0)
      (effects (font (size 1.27 1.27)) (justify left bottom) hide)
    )
    (property "Public" "False" (at 162.56 218.44 0)
      (effects (font (size 1.27 1.27)) (justify left bottom) hide)
    )
    (pin "1")
    (pin "2")
    (instances
      (project "ecp5-dc-scm"
        (path ""
          (reference "R37") (unit 1)
        )
      )
    )
  )

  (symbol (lib_id "antmicroResistors0402:R_10k_0402") (at 124.46 238.76 270) (mirror x) (unit 1)
    (in_bom yes) (on_board yes) (dnp no)
    (property "Reference" "R41" (at 123.19 228.6 0)
      (effects (font (size 1.524 1.524)) (justify right))
    )
    (property "Value" "R_10k_0402" (at 120.65 238.76 0)
      (effects (font (size 1.524 1.524)) hide)
    )
    (property "Footprint" "antmicro-footprints:R_0402_1005Metric" (at 129.54 233.68 0)
      (effects (font (size 1.524 1.524)) (justify left) hide)
    )
    (property "Datasheet" "https://www.bourns.com/docs/product-datasheets/cr.pdf" (at 124.46 238.76 0)
      (effects (font (size 1.27 1.27)) hide)
    )
    (property "Manufacturer" "Bourns" (at 134.62 233.68 0)
      (effects (font (size 1.524 1.524)) (justify left) hide)
    )
    (property "MPN" "CR0402-FX-1002GLF" (at 132.08 233.68 0)
      (effects (font (size 1.524 1.524)) (justify left) hide)
    )
    (property "Val" "10k" (at 123.19 238.76 0)
      (effects (font (size 1.27 1.27)) (justify right))
    )
    (property "License" "Apache-2.0" (at 99.06 218.44 0)
      (effects (font (size 1.27 1.27) (thickness 0.15)) (justify left bottom) hide)
    )
    (property "Author" "Antmicro" (at 96.52 218.44 0)
      (effects (font (size 1.27 1.27) (thickness 0.15)) (justify left bottom) hide)
    )
    (property "Tolerance" "1%" (at 114.3 218.44 0)
      (effects (font (size 1.27 1.27)) (justify left bottom) hide)
    )
    (property "Public" "False" (at 93.98 218.44 0)
      (effects (font (size 1.27 1.27)) (justify left bottom) hide)
    )
    (pin "1")
    (pin "2")
    (instances
      (project "ecp5-dc-scm"
        (path ""
          (reference "R41") (unit 1)
        )
      )
    )
  )

  (symbol (lib_id "antmicroCapacitors0402:C_470n_0402") (at 170.18 256.54 90) (unit 1)
    (in_bom yes) (on_board yes) (dnp no) (fields_autoplaced)
    (property "Reference" "C43" (at 172.72 252.7236 90)
      (effects (font (size 1.524 1.524)) (justify right))
    )
    (property "Value" "C_470n_0402" (at 173.99 256.54 0)
      (effects (font (size 1.524 1.524)) hide)
    )
    (property "Footprint" "antmicro-footprints:C_0402_1005Metric" (at 165.1 251.46 0)
      (effects (font (size 1.524 1.524)) (justify left) hide)
    )
    (property "Datasheet" "https://product.tdk.com/en/search/capacitor/ceramic/mlcc/info?part_no=C1005X5R1E474M050BB" (at 170.18 256.54 0)
      (effects (font (size 1.27 1.27)) hide)
    )
    (property "Manufacturer" "TDK" (at 160.02 251.46 0)
      (effects (font (size 1.524 1.524)) (justify left) hide)
    )
    (property "MPN" "C1005X5R1E474M050BB" (at 162.56 251.46 0)
      (effects (font (size 1.524 1.524)) (justify left) hide)
    )
    (property "Val" "470n" (at 172.72 255.2636 90)
      (effects (font (size 1.27 1.27)) (justify right))
    )
    (property "License" "Apache-2.0" (at 193.04 236.22 0)
      (effects (font (size 1.27 1.27) (thickness 0.15)) (justify left bottom) hide)
    )
    (property "Author" "Antmicro" (at 195.58 236.22 0)
      (effects (font (size 1.27 1.27) (thickness 0.15)) (justify left bottom) hide)
    )
    (property "Voltage" "" (at 198.12 236.22 0)
      (effects (font (size 1.27 1.27)) (justify left bottom) hide)
    )
    (property "Dielectric" "" (at 200.66 236.22 0)
      (effects (font (size 1.27 1.27)) (justify left bottom) hide)
    )
    (property "Public" "False" (at 203.2 236.22 0)
      (effects (font (size 1.27 1.27)) (justify left bottom) hide)
    )
    (pin "1")
    (pin "2")
    (instances
      (project "ecp5-dc-scm"
        (path ""
          (reference "C43") (unit 1)
        )
      )
    )
  )

  (symbol (lib_id "antmicropower:GND") (at 170.18 261.62 0) (unit 1)
    (in_bom yes) (on_board yes) (dnp no)
    (property "Reference" "#PWR016" (at 170.18 267.97 0)
      (effects (font (size 1.27 1.27)) hide)
    )
    (property "Value" "GND" (at 170.307 266.0142 0)
      (effects (font (size 1.27 1.27)))
    )
    (property "Footprint" "" (at 170.18 261.62 0)
      (effects (font (size 1.27 1.27)) hide)
    )
    (property "Datasheet" "" (at 170.18 261.62 0)
      (effects (font (size 1.27 1.27)) hide)
    )
    (property "Author" "Antmicro" (at 179.07 269.24 0)
      (effects (font (size 1.27 1.27) (thickness 0.15)) (justify left bottom) hide)
    )
    (property "License" "Apache-2.0" (at 179.07 271.78 0)
      (effects (font (size 1.27 1.27) (thickness 0.15)) (justify left bottom) hide)
    )
    (pin "1")
    (instances
      (project "ecp5-dc-scm"
        (path ""
          (reference "#PWR016") (unit 1)
        )
      )
    )
  )

  (symbol (lib_id "antmicroResistors0402:R_10k_0402") (at 128.27 238.76 90) (unit 1)
    (in_bom yes) (on_board yes) (dnp no)
    (property "Reference" "R33" (at 127 228.6 0)
      (effects (font (size 1.524 1.524)) (justify right))
    )
    (property "Value" "R_10k_0402" (at 132.08 238.76 0)
      (effects (font (size 1.524 1.524)) hide)
    )
    (property "Footprint" "antmicro-footprints:R_0402_1005Metric" (at 123.19 233.68 0)
      (effects (font (size 1.524 1.524)) (justify left) hide)
    )
    (property "Datasheet" "https://www.bourns.com/docs/product-datasheets/cr.pdf" (at 128.27 238.76 0)
      (effects (font (size 1.27 1.27)) hide)
    )
    (property "Manufacturer" "Bourns" (at 118.11 233.68 0)
      (effects (font (size 1.524 1.524)) (justify left) hide)
    )
    (property "MPN" "CR0402-FX-1002GLF" (at 120.65 233.68 0)
      (effects (font (size 1.524 1.524)) (justify left) hide)
    )
    (property "Val" "10k" (at 127 238.76 0)
      (effects (font (size 1.27 1.27)) (justify right))
    )
    (property "License" "Apache-2.0" (at 153.67 218.44 0)
      (effects (font (size 1.27 1.27) (thickness 0.15)) (justify left bottom) hide)
    )
    (property "Author" "Antmicro" (at 156.21 218.44 0)
      (effects (font (size 1.27 1.27) (thickness 0.15)) (justify left bottom) hide)
    )
    (property "Tolerance" "1%" (at 138.43 218.44 0)
      (effects (font (size 1.27 1.27)) (justify left bottom) hide)
    )
    (property "Public" "False" (at 158.75 218.44 0)
      (effects (font (size 1.27 1.27)) (justify left bottom) hide)
    )
    (pin "1")
    (pin "2")
    (instances
      (project "ecp5-dc-scm"
        (path ""
          (reference "R33") (unit 1)
        )
      )
    )
  )

  (symbol (lib_id "antmicropower:GND") (at 162.56 261.62 0) (unit 1)
    (in_bom yes) (on_board yes) (dnp no)
    (property "Reference" "#PWR020" (at 162.56 267.97 0)
      (effects (font (size 1.27 1.27)) hide)
    )
    (property "Value" "GND" (at 162.687 266.0142 0)
      (effects (font (size 1.27 1.27)))
    )
    (property "Footprint" "" (at 162.56 261.62 0)
      (effects (font (size 1.27 1.27)) hide)
    )
    (property "Datasheet" "" (at 162.56 261.62 0)
      (effects (font (size 1.27 1.27)) hide)
    )
    (property "Author" "Antmicro" (at 171.45 269.24 0)
      (effects (font (size 1.27 1.27) (thickness 0.15)) (justify left bottom) hide)
    )
    (property "License" "Apache-2.0" (at 171.45 271.78 0)
      (effects (font (size 1.27 1.27) (thickness 0.15)) (justify left bottom) hide)
    )
    (pin "1")
    (instances
      (project "ecp5-dc-scm"
        (path ""
          (reference "#PWR020") (unit 1)
        )
      )
    )
  )

  (symbol (lib_id "antmicroGenericPinSockets:PinSocket_2x6_P2.54mm_Drill1.02mm_PMOD") (at 280.67 209.55 0) (unit 1)
    (in_bom yes) (on_board yes) (dnp no) (fields_autoplaced)
    (property "Reference" "J4" (at 285.75 203.2 0)
      (effects (font (size 1.524 1.524)))
    )
    (property "Value" "PinSocket_2x6_P2.54mm_Drill1.02mm_PMOD" (at 285.75 205.74 0)
      (effects (font (size 1.524 1.524)))
    )
    (property "Footprint" "antmicro-footprints:PinSocket_2x6_P2.54mm_Drill1.02mm_PMOD" (at 285.75 204.47 0)
      (effects (font (size 1.524 1.524)) (justify left) hide)
    )
    (property "Datasheet" "https://cdn.harwin.com/pdfs/M20-783.pdf" (at 285.75 201.93 0)
      (effects (font (size 1.524 1.524)) (justify left) hide)
    )
    (property "MPN" "M20-7830642" (at 285.75 196.85 0)
      (effects (font (size 1.524 1.524)) (justify left) hide)
    )
    (property "Manufacturer" "Harwin" (at 285.75 194.31 0)
      (effects (font (size 1.524 1.524)) (justify left) hide)
    )
    (property "Author" "Antmicro" (at 306.07 229.87 0)
      (effects (font (size 1.27 1.27) (thickness 0.15)) (justify left bottom) hide)
    )
    (property "License" "Apache-2.0" (at 306.07 232.41 0)
      (effects (font (size 1.27 1.27) (thickness 0.15)) (justify left bottom) hide)
    )
    (pin "1")
    (pin "10")
    (pin "11")
    (pin "12")
    (pin "2")
    (pin "3")
    (pin "4")
    (pin "5")
    (pin "6")
    (pin "7")
    (pin "8")
    (pin "9")
    (instances
      (project "ecp5-dc-scm"
        (path ""
          (reference "J4") (unit 1)
        )
      )
    )
  )

  (symbol (lib_id "antmicropower:GND") (at 275.59 132.08 0) (mirror y) (unit 1)
    (in_bom yes) (on_board yes) (dnp no)
    (property "Reference" "#PWR024" (at 275.59 138.43 0)
      (effects (font (size 1.27 1.27)) hide)
    )
    (property "Value" "GND" (at 275.463 136.4742 0)
      (effects (font (size 1.27 1.27)))
    )
    (property "Footprint" "" (at 275.59 132.08 0)
      (effects (font (size 1.27 1.27)) hide)
    )
    (property "Datasheet" "" (at 275.59 132.08 0)
      (effects (font (size 1.27 1.27)) hide)
    )
    (property "Author" "Antmicro" (at 266.7 139.7 0)
      (effects (font (size 1.27 1.27) (thickness 0.15)) (justify left bottom) hide)
    )
    (property "License" "Apache-2.0" (at 266.7 142.24 0)
      (effects (font (size 1.27 1.27) (thickness 0.15)) (justify left bottom) hide)
    )
    (pin "1")
    (instances
      (project "ecp5-dc-scm"
        (path ""
          (reference "#PWR024") (unit 1)
        )
      )
    )
  )

  (symbol (lib_id "antmicroMemory:W25Q32JVSSIQ") (at 142.24 121.92 0) (unit 1)
    (in_bom yes) (on_board yes) (dnp no) (fields_autoplaced)
    (property "Reference" "U4" (at 151.765 114.3 0)
      (effects (font (size 1.27 1.27) (thickness 0.15)))
    )
    (property "Value" "W25Q32JVSSIQ" (at 175.26 128.27 0)
      (effects (font (size 1.27 1.27) (thickness 0.15)) (justify left bottom) hide)
    )
    (property "Footprint" "antmicro-footprints:SOIC-8_5.3x5.3x2mm_P1.27mm" (at 175.26 130.81 0)
      (effects (font (size 1.27 1.27) (thickness 0.15)) (justify left bottom) hide)
    )
    (property "Datasheet" "https://www.mouser.com/datasheet/2/949/w25q32jv_revg_03272018_plus-1489806.pdf" (at 175.26 133.35 0)
      (effects (font (size 1.27 1.27) (thickness 0.15)) (justify left bottom) hide)
    )
    (property "MPN" "W25Q32JVSSIQ" (at 151.765 116.84 0)
      (effects (font (size 1.27 1.27) (thickness 0.15)))
    )
    (property "Manufacturer" "Winbond" (at 175.26 138.43 0)
      (effects (font (size 1.27 1.27) (thickness 0.15)) (justify left bottom) hide)
    )
    (property "Author" "Antmicro" (at 175.26 140.97 0)
      (effects (font (size 1.27 1.27) (thickness 0.15)) (justify left bottom) hide)
    )
    (property "License" "Apache-2.0" (at 175.26 143.51 0)
      (effects (font (size 1.27 1.27) (thickness 0.15)) (justify left bottom) hide)
    )
    (pin "3")
    (pin "6")
    (pin "7")
    (pin "2")
    (pin "1")
    (pin "8")
    (pin "5")
    (pin "4")
    (instances
      (project "ecp5-dc-scm"
        (path ""
          (reference "U4") (unit 1)
        )
      )
    )
  )

  (symbol (lib_id "antmicropower:GND") (at 162.56 76.2 0) (unit 1)
    (in_bom yes) (on_board yes) (dnp no)
    (property "Reference" "#PWR022" (at 162.56 82.55 0)
      (effects (font (size 1.27 1.27)) hide)
    )
    (property "Value" "GND" (at 162.687 80.5942 0)
      (effects (font (size 1.27 1.27)))
    )
    (property "Footprint" "" (at 162.56 76.2 0)
      (effects (font (size 1.27 1.27)) hide)
    )
    (property "Datasheet" "" (at 162.56 76.2 0)
      (effects (font (size 1.27 1.27)) hide)
    )
    (property "Author" "Antmicro" (at 171.45 83.82 0)
      (effects (font (size 1.27 1.27) (thickness 0.15)) (justify left bottom) hide)
    )
    (property "License" "Apache-2.0" (at 171.45 86.36 0)
      (effects (font (size 1.27 1.27) (thickness 0.15)) (justify left bottom) hide)
    )
    (pin "1")
    (instances
      (project "ecp5-dc-scm"
        (path ""
          (reference "#PWR022") (unit 1)
        )
      )
    )
  )

  (symbol (lib_id "antmicroMemory:W25Q32JVSSIQ") (at 142.24 62.23 0) (unit 1)
    (in_bom yes) (on_board yes) (dnp no) (fields_autoplaced)
    (property "Reference" "U5" (at 151.765 54.61 0)
      (effects (font (size 1.27 1.27) (thickness 0.15)))
    )
    (property "Value" "W25Q32JVSSIQ" (at 175.26 68.58 0)
      (effects (font (size 1.27 1.27) (thickness 0.15)) (justify left bottom) hide)
    )
    (property "Footprint" "antmicro-footprints:SOIC-8_5.3x5.3x2mm_P1.27mm" (at 175.26 71.12 0)
      (effects (font (size 1.27 1.27) (thickness 0.15)) (justify left bottom) hide)
    )
    (property "Datasheet" "https://www.mouser.com/datasheet/2/949/w25q32jv_revg_03272018_plus-1489806.pdf" (at 175.26 73.66 0)
      (effects (font (size 1.27 1.27) (thickness 0.15)) (justify left bottom) hide)
    )
    (property "MPN" "W25Q32JVSSIQ" (at 151.765 57.15 0)
      (effects (font (size 1.27 1.27) (thickness 0.15)))
    )
    (property "Manufacturer" "Winbond" (at 175.26 78.74 0)
      (effects (font (size 1.27 1.27) (thickness 0.15)) (justify left bottom) hide)
    )
    (property "Author" "Antmicro" (at 175.26 81.28 0)
      (effects (font (size 1.27 1.27) (thickness 0.15)) (justify left bottom) hide)
    )
    (property "License" "Apache-2.0" (at 175.26 83.82 0)
      (effects (font (size 1.27 1.27) (thickness 0.15)) (justify left bottom) hide)
    )
    (pin "3")
    (pin "6")
    (pin "7")
    (pin "2")
    (pin "1")
    (pin "8")
    (pin "5")
    (pin "4")
    (instances
      (project "ecp5-dc-scm"
        (path ""
          (reference "U5") (unit 1)
        )
      )
    )
  )

  (symbol (lib_id "antmicroMemory:W25Q32JVSSIQ") (at 142.24 194.31 0) (unit 1)
    (in_bom yes) (on_board yes) (dnp no) (fields_autoplaced)
    (property "Reference" "U3" (at 151.765 186.69 0)
      (effects (font (size 1.27 1.27) (thickness 0.15)))
    )
    (property "Value" "W25Q32JVSSIQ" (at 175.26 200.66 0)
      (effects (font (size 1.27 1.27) (thickness 0.15)) (justify left bottom) hide)
    )
    (property "Footprint" "antmicro-footprints:SOIC-8_5.3x5.3x2mm_P1.27mm" (at 175.26 203.2 0)
      (effects (font (size 1.27 1.27) (thickness 0.15)) (justify left bottom) hide)
    )
    (property "Datasheet" "https://www.mouser.com/datasheet/2/949/w25q32jv_revg_03272018_plus-1489806.pdf" (at 175.26 205.74 0)
      (effects (font (size 1.27 1.27) (thickness 0.15)) (justify left bottom) hide)
    )
    (property "MPN" "W25Q32JVSSIQ" (at 151.765 189.23 0)
      (effects (font (size 1.27 1.27) (thickness 0.15)))
    )
    (property "Manufacturer" "Winbond" (at 175.26 210.82 0)
      (effects (font (size 1.27 1.27) (thickness 0.15)) (justify left bottom) hide)
    )
    (property "Author" "Antmicro" (at 175.26 213.36 0)
      (effects (font (size 1.27 1.27) (thickness 0.15)) (justify left bottom) hide)
    )
    (property "License" "Apache-2.0" (at 175.26 215.9 0)
      (effects (font (size 1.27 1.27) (thickness 0.15)) (justify left bottom) hide)
    )
    (pin "3")
    (pin "6")
    (pin "7")
    (pin "2")
    (pin "1")
    (pin "8")
    (pin "5")
    (pin "4")
    (instances
      (project "ecp5-dc-scm"
        (path ""
          (reference "U3") (unit 1)
        )
      )
    )
  )

  (symbol (lib_id "antmicroMemory:W25Q32JVSSIQ") (at 142.24 247.65 0) (unit 1)
    (in_bom yes) (on_board yes) (dnp no) (fields_autoplaced)
    (property "Reference" "U2" (at 151.765 240.03 0)
      (effects (font (size 1.27 1.27) (thickness 0.15)))
    )
    (property "Value" "W25Q32JVSSIQ" (at 175.26 254 0)
      (effects (font (size 1.27 1.27) (thickness 0.15)) (justify left bottom) hide)
    )
    (property "Footprint" "antmicro-footprints:SOIC-8_5.3x5.3x2mm_P1.27mm" (at 175.26 256.54 0)
      (effects (font (size 1.27 1.27) (thickness 0.15)) (justify left bottom) hide)
    )
    (property "Datasheet" "https://www.mouser.com/datasheet/2/949/w25q32jv_revg_03272018_plus-1489806.pdf" (at 175.26 259.08 0)
      (effects (font (size 1.27 1.27) (thickness 0.15)) (justify left bottom) hide)
    )
    (property "MPN" "W25Q32JVSSIQ" (at 151.765 242.57 0)
      (effects (font (size 1.27 1.27) (thickness 0.15)))
    )
    (property "Manufacturer" "Winbond" (at 175.26 264.16 0)
      (effects (font (size 1.27 1.27) (thickness 0.15)) (justify left bottom) hide)
    )
    (property "Author" "Antmicro" (at 175.26 266.7 0)
      (effects (font (size 1.27 1.27) (thickness 0.15)) (justify left bottom) hide)
    )
    (property "License" "Apache-2.0" (at 175.26 269.24 0)
      (effects (font (size 1.27 1.27) (thickness 0.15)) (justify left bottom) hide)
    )
    (pin "3")
    (pin "6")
    (pin "7")
    (pin "2")
    (pin "1")
    (pin "8")
    (pin "5")
    (pin "4")
    (instances
      (project "ecp5-dc-scm"
        (path ""
          (reference "U2") (unit 1)
        )
      )
    )
  )

  (symbol (lib_id "antmicropower:GND") (at 163.83 137.16 0) (unit 1)
    (in_bom yes) (on_board yes) (dnp no)
    (property "Reference" "#PWR021" (at 163.83 143.51 0)
      (effects (font (size 1.27 1.27)) hide)
    )
    (property "Value" "GND" (at 163.957 141.5542 0)
      (effects (font (size 1.27 1.27)))
    )
    (property "Footprint" "" (at 163.83 137.16 0)
      (effects (font (size 1.27 1.27)) hide)
    )
    (property "Datasheet" "" (at 163.83 137.16 0)
      (effects (font (size 1.27 1.27)) hide)
    )
    (property "Author" "Antmicro" (at 172.72 144.78 0)
      (effects (font (size 1.27 1.27) (thickness 0.15)) (justify left bottom) hide)
    )
    (property "License" "Apache-2.0" (at 172.72 147.32 0)
      (effects (font (size 1.27 1.27) (thickness 0.15)) (justify left bottom) hide)
    )
    (pin "1")
    (instances
      (project "ecp5-dc-scm"
        (path ""
          (reference "#PWR021") (unit 1)
        )
      )
    )
  )

  (symbol (lib_id "antmicropower:GND") (at 162.56 208.28 0) (unit 1)
    (in_bom yes) (on_board yes) (dnp no)
    (property "Reference" "#PWR099" (at 162.56 214.63 0)
      (effects (font (size 1.27 1.27)) hide)
    )
    (property "Value" "GND" (at 162.687 212.6742 0)
      (effects (font (size 1.27 1.27)))
    )
    (property "Footprint" "" (at 162.56 208.28 0)
      (effects (font (size 1.27 1.27)) hide)
    )
    (property "Datasheet" "" (at 162.56 208.28 0)
      (effects (font (size 1.27 1.27)) hide)
    )
    (property "Author" "Antmicro" (at 171.45 215.9 0)
      (effects (font (size 1.27 1.27) (thickness 0.15)) (justify left bottom) hide)
    )
    (property "License" "Apache-2.0" (at 171.45 218.44 0)
      (effects (font (size 1.27 1.27) (thickness 0.15)) (justify left bottom) hide)
    )
    (pin "1")
    (instances
      (project "ecp5-dc-scm"
        (path ""
          (reference "#PWR099") (unit 1)
        )
      )
    )
  )

  (symbol (lib_id "antmicroMechanicalParts:Spacer_Drill3.7mm_H4mm_9774040151R") (at 278.13 153.67 0) (unit 1)
    (in_bom yes) (on_board yes) (dnp no) (fields_autoplaced)
    (property "Reference" "H2" (at 287.02 152.4 0)
      (effects (font (size 1.27 1.27) (thickness 0.15)) (justify left))
    )
    (property "Value" "Spacer_Drill3.7mm_H4mm_9774040151R" (at 287.02 154.94 0)
      (effects (font (size 1.27 1.27) (thickness 0.15)) (justify left))
    )
    (property "Footprint" "antmicro-footprints:Spacer_Drill3.7mm_H4mm_9774040151R" (at 300.99 161.29 0)
      (effects (font (size 1.27 1.27) (thickness 0.15)) (justify left bottom) hide)
    )
    (property "Datasheet" "https://www.we-online.com/components/products/datasheet/9774040151R.pdf" (at 300.99 163.83 0)
      (effects (font (size 1.27 1.27) (thickness 0.15)) (justify left bottom) hide)
    )
    (property "Manufacturer" "Würth Elektronik" (at 300.99 166.37 0)
      (effects (font (size 1.27 1.27) (thickness 0.15)) (justify left bottom) hide)
    )
    (property "MPN" "9774040151R" (at 300.99 168.91 0)
      (effects (font (size 1.27 1.27) (thickness 0.15)) (justify left bottom) hide)
    )
    (property "Author" "Antmicro" (at 300.99 171.45 0)
      (effects (font (size 1.27 1.27) (thickness 0.15)) (justify left bottom) hide)
    )
    (property "Public" "False" (at 300.99 166.37 0)
      (effects (font (size 1.27 1.27)) (justify left bottom) hide)
    )
    (property "License" "Apache-2.0" (at 300.99 173.99 0)
      (effects (font (size 1.27 1.27) (thickness 0.15)) (justify left bottom) hide)
    )
    (pin "1")
    (instances
      (project "ecp5-dc-scm"
        (path ""
          (reference "H2") (unit 1)
        )
      )
    )
  )

  (symbol (lib_id "antmicroB2BConnectors:Plug_Molex_SlimStack_2x25_529910508") (at 288.29 125.73 180) (unit 1)
    (in_bom yes) (on_board yes) (dnp no)
    (property "Reference" "J3" (at 282.575 57.15 0)
      (effects (font (size 1.27 1.27) (thickness 0.15)))
    )
    (property "Value" "Plug_Molex_SlimStack_2x25_529910508" (at 262.89 120.65 0)
      (effects (font (size 1.27 1.27) (thickness 0.15)) (justify left bottom) hide)
    )
    (property "Footprint" "antmicro-footprints:Conn_Plug_Molex_SlimStack_2x25_529910508" (at 262.89 118.11 0)
      (effects (font (size 1.27 1.27) (thickness 0.15)) (justify left bottom) hide)
    )
    (property "Datasheet" "https://www.molex.com/en-us/products/part-detail/529910508?display=pdf" (at 262.89 115.57 0)
      (effects (font (size 1.27 1.27) (thickness 0.15)) (justify left bottom) hide)
    )
    (property "MPN" "529910508" (at 282.575 59.69 0)
      (effects (font (size 1.27 1.27) (thickness 0.15)))
    )
    (property "Manufacturer" "Molex" (at 262.89 113.03 0)
      (effects (font (size 1.27 1.27) (thickness 0.15)) (justify left bottom) hide)
    )
    (property "Author" "Antmicro" (at 262.89 107.95 0)
      (effects (font (size 1.27 1.27) (thickness 0.15)) (justify left bottom) hide)
    )
    (property "License" "Apache-2.0" (at 262.89 105.41 0)
      (effects (font (size 1.27 1.27) (thickness 0.15)) (justify left bottom) hide)
    )
    (property "Pitch " "0.5 mm" (at 262.89 110.49 0)
      (effects (font (size 1.27 1.27)) (justify left bottom) hide)
    )
    (pin "25")
    (pin "50")
    (pin "38")
    (pin "27")
    (pin "39")
    (pin "23")
    (pin "46")
    (pin "21")
    (pin "45")
    (pin "47")
    (pin "8")
    (pin "7")
    (pin "44")
    (pin "35")
    (pin "48")
    (pin "20")
    (pin "22")
    (pin "18")
    (pin "16")
    (pin "12")
    (pin "13")
    (pin "15")
    (pin "2")
    (pin "24")
    (pin "14")
    (pin "10")
    (pin "11")
    (pin "34")
    (pin "1")
    (pin "31")
    (pin "9")
    (pin "41")
    (pin "17")
    (pin "33")
    (pin "40")
    (pin "4")
    (pin "3")
    (pin "29")
    (pin "30")
    (pin "43")
    (pin "36")
    (pin "5")
    (pin "37")
    (pin "19")
    (pin "42")
    (pin "6")
    (pin "26")
    (pin "32")
    (pin "49")
    (pin "28")
    (instances
      (project "ecp5-dc-scm"
        (path ""
          (reference "J3") (unit 1)
        )
      )
    )
  )
)
